(kicad_sch
	(version 20250114)
	(generator "eeschema")
	(generator_version "9.0")
	(paper "A3")
	(title_block
		(title "Artix - Datacenter Secure Control Module (DC-SCM)")
		(date "2024-11-06")
		(rev "1.1.3")
	)
	(text "DVDDL decoupling"
		(exclude_from_sim no)
		(at 266.065 66.04 0)
		(effects
			(font
				(size 2 2)
				(thickness 0.5994)
				(bold yes)
			)
			(justify left bottom)
		)
	)
	(text "DVDDL"
		(exclude_from_sim no)
		(at 242.57 114.3 0)
		(effects
			(font
				(size 1.27 1.27)
			)
			(justify left bottom)
		)
	)
	(text "MODE0\n"
		(exclude_from_sim no)
		(at 78.74 123.19 0)
		(effects
			(font
				(size 1.27 1.27)
			)
			(justify left bottom)
		)
	)
	(text "PHY"
		(exclude_from_sim no)
		(at 215.265 99.695 0)
		(effects
			(font
				(size 2 2)
				(thickness 0.5994)
				(bold yes)
			)
			(justify left bottom)
		)
	)
	(text "MODE1"
		(exclude_from_sim no)
		(at 78.74 120.65 0)
		(effects
			(font
				(size 1.27 1.27)
			)
			(justify left bottom)
		)
	)
	(text "default:\nMODE[3:0] : 1111 (see datasheet table 2-2)\nPHYAD[4:0]: 00111 \nCLK125_EN: 1, enabled\nLED_MODE: 1, Individual-LED"
		(exclude_from_sim no)
		(at 35.56 150.495 0)
		(effects
			(font
				(size 1.27 1.27)
			)
			(justify left bottom)
		)
	)
	(text "AVDDL_PLL decoupling"
		(exclude_from_sim no)
		(at 266.065 104.775 0)
		(effects
			(font
				(size 2 2)
				(thickness 0.5994)
				(bold yes)
			)
			(justify left bottom)
		)
	)
	(text "MODE3"
		(exclude_from_sim no)
		(at 78.74 115.57 0)
		(effects
			(font
				(size 1.27 1.27)
			)
			(justify left bottom)
		)
	)
	(text "MODE2"
		(exclude_from_sim no)
		(at 78.74 118.11 0)
		(effects
			(font
				(size 1.27 1.27)
			)
			(justify left bottom)
		)
	)
	(text "PHYAD1"
		(exclude_from_sim no)
		(at 78.74 129.54 0)
		(effects
			(font
				(size 1.27 1.27)
			)
			(justify left bottom)
		)
	)
	(text "PHYAD2"
		(exclude_from_sim no)
		(at 78.74 132.08 0)
		(effects
			(font
				(size 1.27 1.27)
			)
			(justify left bottom)
		)
	)
	(text "AVDDH decoupling"
		(exclude_from_sim no)
		(at 149.225 104.775 0)
		(effects
			(font
				(size 2 2)
				(thickness 0.5994)
				(bold yes)
			)
			(justify left bottom)
		)
	)
	(text "DVDDH"
		(exclude_from_sim no)
		(at 188.595 114.3 0)
		(effects
			(font
				(size 1.27 1.27)
			)
			(justify left bottom)
		)
	)
	(text "CLK125_EN"
		(exclude_from_sim no)
		(at 78.74 135.255 0)
		(effects
			(font
				(size 1.27 1.27)
			)
			(justify left bottom)
		)
	)
	(text "AVDDL decoupling"
		(exclude_from_sim no)
		(at 266.065 85.725 0)
		(effects
			(font
				(size 2 2)
				(thickness 0.5994)
				(bold yes)
			)
			(justify left bottom)
		)
	)
	(text "LED_MODE"
		(exclude_from_sim no)
		(at 78.74 138.43 0)
		(effects
			(font
				(size 1.27 1.27)
			)
			(justify left bottom)
		)
	)
	(text "Pullup resistors"
		(exclude_from_sim no)
		(at 130.81 127 0)
		(effects
			(font
				(size 1.27 1.27)
				(thickness 0.5994)
				(bold yes)
			)
			(justify left bottom)
		)
	)
	(text "Bootstrap configuration"
		(exclude_from_sim no)
		(at 35.56 104.775 0)
		(effects
			(font
				(size 1.27 1.27)
				(thickness 0.5994)
				(bold yes)
			)
			(justify left bottom)
		)
	)
	(text "DVDDH decoupling"
		(exclude_from_sim no)
		(at 149.86 85.09 0)
		(effects
			(font
				(size 2 2)
				(thickness 0.5994)
				(bold yes)
			)
			(justify left bottom)
		)
	)
	(text "RJ45 Connector"
		(exclude_from_sim no)
		(at 316.23 127.635 0)
		(effects
			(font
				(size 2 2)
				(thickness 0.5994)
				(bold yes)
			)
			(justify left bottom)
		)
	)
	(text "PHYAD0"
		(exclude_from_sim no)
		(at 78.74 127 0)
		(effects
			(font
				(size 1.27 1.27)
			)
			(justify left bottom)
		)
	)
	(junction
		(at 283.21 67.31)
		(diameter 0)
		(color 0 0 0 0)
	)
	(junction
		(at 77.47 135.89)
		(diameter 0)
		(color 0 0 0 0)
	)
	(junction
		(at 168.91 106.68)
		(diameter 0)
		(color 0 0 0 0)
	)
	(junction
		(at 132.08 128.27)
		(diameter 0)
		(color 0 0 0 0)
	)
	(junction
		(at 177.8 173.99)
		(diameter 0)
		(color 0 0 0 0)
	)
	(junction
		(at 77.47 127)
		(diameter 0)
		(color 0 0 0 0)
	)
	(junction
		(at 266.7 86.36)
		(diameter 0)
		(color 0 0 0 0)
	)
	(junction
		(at 242.57 173.99)
		(diameter 0)
		(color 0 0 0 0)
	)
	(junction
		(at 77.47 123.19)
		(diameter 0)
		(color 0 0 0 0)
	)
	(junction
		(at 132.08 86.36)
		(diameter 0)
		(color 0 0 0 0)
	)
	(junction
		(at 168.91 86.36)
		(diameter 0)
		(color 0 0 0 0)
	)
	(junction
		(at 290.83 86.36)
		(diameter 0)
		(color 0 0 0 0)
	)
	(junction
		(at 77.47 120.65)
		(diameter 0)
		(color 0 0 0 0)
	)
	(junction
		(at 274.32 106.68)
		(diameter 0)
		(color 0 0 0 0)
	)
	(junction
		(at 274.32 67.31)
		(diameter 0)
		(color 0 0 0 0)
	)
	(junction
		(at 316.23 67.31)
		(diameter 0)
		(color 0 0 0 0)
	)
	(junction
		(at 177.8 110.49)
		(diameter 0)
		(color 0 0 0 0)
	)
	(junction
		(at 144.78 86.36)
		(diameter 0)
		(color 0 0 0 0)
	)
	(junction
		(at 330.2 86.36)
		(diameter 0)
		(color 0 0 0 0)
	)
	(junction
		(at 77.47 132.08)
		(diameter 0)
		(color 0 0 0 0)
	)
	(junction
		(at 152.4 106.68)
		(diameter 0)
		(color 0 0 0 0)
	)
	(junction
		(at 177.8 184.15)
		(diameter 0)
		(color 0 0 0 0)
	)
	(junction
		(at 191.77 173.99)
		(diameter 0)
		(color 0 0 0 0)
	)
	(junction
		(at 307.34 67.31)
		(diameter 0)
		(color 0 0 0 0)
	)
	(junction
		(at 283.21 86.36)
		(diameter 0)
		(color 0 0 0 0)
	)
	(junction
		(at 77.47 118.11)
		(diameter 0)
		(color 0 0 0 0)
	)
	(junction
		(at 77.47 129.54)
		(diameter 0)
		(color 0 0 0 0)
	)
	(junction
		(at 152.4 86.36)
		(diameter 0)
		(color 0 0 0 0)
	)
	(junction
		(at 160.02 106.68)
		(diameter 0)
		(color 0 0 0 0)
	)
	(junction
		(at 290.83 106.68)
		(diameter 0)
		(color 0 0 0 0)
	)
	(junction
		(at 330.2 67.31)
		(diameter 0)
		(color 0 0 0 0)
	)
	(junction
		(at 161.29 86.36)
		(diameter 0)
		(color 0 0 0 0)
	)
	(junction
		(at 323.85 67.31)
		(diameter 0)
		(color 0 0 0 0)
	)
	(junction
		(at 259.08 86.36)
		(diameter 0)
		(color 0 0 0 0)
	)
	(junction
		(at 242.57 176.53)
		(diameter 0)
		(color 0 0 0 0)
	)
	(junction
		(at 257.81 67.31)
		(diameter 0)
		(color 0 0 0 0)
	)
	(junction
		(at 266.7 120.65)
		(diameter 0)
		(color 0 0 0 0)
	)
	(junction
		(at 283.21 106.68)
		(diameter 0)
		(color 0 0 0 0)
	)
	(junction
		(at 299.72 67.31)
		(diameter 0)
		(color 0 0 0 0)
	)
	(junction
		(at 191.77 184.15)
		(diameter 0)
		(color 0 0 0 0)
	)
	(junction
		(at 290.83 67.31)
		(diameter 0)
		(color 0 0 0 0)
	)
	(junction
		(at 77.47 115.57)
		(diameter 0)
		(color 0 0 0 0)
	)
	(junction
		(at 266.7 67.31)
		(diameter 0)
		(color 0 0 0 0)
	)
	(junction
		(at 274.32 86.36)
		(diameter 0)
		(color 0 0 0 0)
	)
	(junction
		(at 242.57 171.45)
		(diameter 0)
		(color 0 0 0 0)
	)
	(junction
		(at 177.8 86.36)
		(diameter 0)
		(color 0 0 0 0)
	)
	(no_connect
		(at 241.3 123.19)
	)
	(wire
		(pts
			(xy 177.8 118.11) (xy 196.85 118.11)
		)
		(stroke
			(width 0)
			(type default)
		)
	)
	(wire
		(pts
			(xy 55.88 132.08) (xy 66.04 132.08)
		)
		(stroke
			(width 0)
			(type default)
		)
	)
	(wire
		(pts
			(xy 317.5 106.68) (xy 330.2 106.68)
		)
		(stroke
			(width 0)
			(type default)
		)
	)
	(polyline
		(pts
			(xy 99.06 101.6) (xy 99.06 152.4)
		)
		(stroke
			(width 0)
			(type dash)
		)
	)
	(wire
		(pts
			(xy 257.81 86.36) (xy 259.08 86.36)
		)
		(stroke
			(width 0)
			(type default)
		)
	)
	(wire
		(pts
			(xy 140.97 106.68) (xy 152.4 106.68)
		)
		(stroke
			(width 0)
			(type default)
		)
	)
	(wire
		(pts
			(xy 290.83 67.31) (xy 290.83 68.58)
		)
		(stroke
			(width 0)
			(type default)
		)
	)
	(wire
		(pts
			(xy 320.04 158.75) (xy 320.04 160.02)
		)
		(stroke
			(width 0)
			(type default)
		)
	)
	(wire
		(pts
			(xy 266.7 86.36) (xy 274.32 86.36)
		)
		(stroke
			(width 0)
			(type default)
		)
	)
	(wire
		(pts
			(xy 189.23 121.92) (xy 196.85 121.92)
		)
		(stroke
			(width 0)
			(type default)
		)
	)
	(wire
		(pts
			(xy 132.08 128.27) (xy 132.08 129.54)
		)
		(stroke
			(width 0)
			(type default)
		)
	)
	(wire
		(pts
			(xy 182.88 173.99) (xy 177.8 173.99)
		)
		(stroke
			(width 0)
			(type default)
		)
	)
	(wire
		(pts
			(xy 241.3 118.11) (xy 257.81 118.11)
		)
		(stroke
			(width 0)
			(type default)
		)
	)
	(wire
		(pts
			(xy 189.23 139.7) (xy 196.85 139.7)
		)
		(stroke
			(width 0)
			(type default)
		)
	)
	(wire
		(pts
			(xy 189.23 156.21) (xy 196.85 156.21)
		)
		(stroke
			(width 0)
			(type default)
		)
	)
	(wire
		(pts
			(xy 191.77 173.99) (xy 187.96 173.99)
		)
		(stroke
			(width 0)
			(type default)
		)
	)
	(wire
		(pts
			(xy 189.23 151.13) (xy 196.85 151.13)
		)
		(stroke
			(width 0)
			(type default)
		)
	)
	(wire
		(pts
			(xy 299.72 156.21) (xy 279.4 156.21)
		)
		(stroke
			(width 0)
			(type default)
		)
	)
	(wire
		(pts
			(xy 241.3 163.83) (xy 242.57 163.83)
		)
		(stroke
			(width 0)
			(type default)
		)
	)
	(wire
		(pts
			(xy 332.74 132.08) (xy 317.5 132.08)
		)
		(stroke
			(width 0)
			(type default)
		)
	)
	(wire
		(pts
			(xy 71.12 132.08) (xy 77.47 132.08)
		)
		(stroke
			(width 0)
			(type default)
		)
	)
	(wire
		(pts
			(xy 257.81 86.36) (xy 257.81 118.11)
		)
		(stroke
			(width 0)
			(type default)
		)
	)
	(wire
		(pts
			(xy 196.85 124.46) (xy 189.23 124.46)
		)
		(stroke
			(width 0)
			(type default)
		)
	)
	(wire
		(pts
			(xy 299.72 137.16) (xy 241.3 137.16)
		)
		(stroke
			(width 0)
			(type default)
		)
	)
	(wire
		(pts
			(xy 295.91 161.29) (xy 295.91 162.56)
		)
		(stroke
			(width 0)
			(type default)
		)
	)
	(wire
		(pts
			(xy 77.47 118.11) (xy 77.47 120.65)
		)
		(stroke
			(width 0)
			(type default)
		)
	)
	(wire
		(pts
			(xy 299.72 149.86) (xy 241.3 149.86)
		)
		(stroke
			(width 0)
			(type default)
		)
	)
	(wire
		(pts
			(xy 77.47 120.65) (xy 77.47 123.19)
		)
		(stroke
			(width 0)
			(type default)
		)
	)
	(wire
		(pts
			(xy 299.72 143.51) (xy 241.3 143.51)
		)
		(stroke
			(width 0)
			(type default)
		)
	)
	(wire
		(pts
			(xy 196.85 163.83) (xy 189.23 163.83)
		)
		(stroke
			(width 0)
			(type default)
		)
	)
	(wire
		(pts
			(xy 184.15 114.3) (xy 196.85 114.3)
		)
		(stroke
			(width 0)
			(type default)
		)
	)
	(wire
		(pts
			(xy 266.7 120.65) (xy 266.7 106.68)
		)
		(stroke
			(width 0)
			(type default)
		)
	)
	(wire
		(pts
			(xy 161.29 86.36) (xy 168.91 86.36)
		)
		(stroke
			(width 0)
			(type default)
		)
	)
	(wire
		(pts
			(xy 144.78 86.36) (xy 152.4 86.36)
		)
		(stroke
			(width 0)
			(type default)
		)
	)
	(wire
		(pts
			(xy 242.57 170.18) (xy 242.57 171.45)
		)
		(stroke
			(width 0)
			(type default)
		)
	)
	(wire
		(pts
			(xy 266.7 86.36) (xy 266.7 87.63)
		)
		(stroke
			(width 0)
			(type default)
		)
	)
	(wire
		(pts
			(xy 316.23 67.31) (xy 316.23 68.58)
		)
		(stroke
			(width 0)
			(type default)
		)
	)
	(wire
		(pts
			(xy 184.15 86.36) (xy 184.15 114.3)
		)
		(stroke
			(width 0)
			(type default)
		)
	)
	(wire
		(pts
			(xy 290.83 106.68) (xy 312.42 106.68)
		)
		(stroke
			(width 0)
			(type default)
		)
	)
	(wire
		(pts
			(xy 189.23 144.78) (xy 196.85 144.78)
		)
		(stroke
			(width 0)
			(type default)
		)
	)
	(wire
		(pts
			(xy 274.32 67.31) (xy 266.7 67.31)
		)
		(stroke
			(width 0)
			(type default)
		)
	)
	(wire
		(pts
			(xy 71.12 118.11) (xy 77.47 118.11)
		)
		(stroke
			(width 0)
			(type default)
		)
	)
	(wire
		(pts
			(xy 290.83 86.36) (xy 290.83 87.63)
		)
		(stroke
			(width 0)
			(type default)
		)
	)
	(wire
		(pts
			(xy 71.12 135.89) (xy 77.47 135.89)
		)
		(stroke
			(width 0)
			(type default)
		)
	)
	(wire
		(pts
			(xy 130.81 86.36) (xy 132.08 86.36)
		)
		(stroke
			(width 0)
			(type default)
		)
	)
	(wire
		(pts
			(xy 274.32 106.68) (xy 283.21 106.68)
		)
		(stroke
			(width 0)
			(type default)
		)
	)
	(wire
		(pts
			(xy 242.57 173.99) (xy 242.57 176.53)
		)
		(stroke
			(width 0)
			(type default)
		)
	)
	(wire
		(pts
			(xy 160.02 106.68) (xy 160.02 107.95)
		)
		(stroke
			(width 0)
			(type default)
		)
	)
	(wire
		(pts
			(xy 189.23 167.64) (xy 196.85 167.64)
		)
		(stroke
			(width 0)
			(type default)
		)
	)
	(wire
		(pts
			(xy 168.91 86.36) (xy 168.91 87.63)
		)
		(stroke
			(width 0)
			(type default)
		)
	)
	(wire
		(pts
			(xy 332.74 67.31) (xy 330.2 67.31)
		)
		(stroke
			(width 0)
			(type default)
		)
	)
	(wire
		(pts
			(xy 242.57 163.83) (xy 242.57 165.1)
		)
		(stroke
			(width 0)
			(type default)
		)
	)
	(wire
		(pts
			(xy 177.8 185.42) (xy 177.8 184.15)
		)
		(stroke
			(width 0)
			(type default)
		)
	)
	(wire
		(pts
			(xy 160.02 106.68) (xy 168.91 106.68)
		)
		(stroke
			(width 0)
			(type default)
		)
	)
	(wire
		(pts
			(xy 266.7 106.68) (xy 274.32 106.68)
		)
		(stroke
			(width 0)
			(type default)
		)
	)
	(wire
		(pts
			(xy 196.85 137.16) (xy 189.23 137.16)
		)
		(stroke
			(width 0)
			(type default)
		)
	)
	(wire
		(pts
			(xy 168.91 106.68) (xy 168.91 107.95)
		)
		(stroke
			(width 0)
			(type default)
		)
	)
	(wire
		(pts
			(xy 330.2 67.31) (xy 323.85 67.31)
		)
		(stroke
			(width 0)
			(type default)
		)
	)
	(wire
		(pts
			(xy 77.47 115.57) (xy 77.47 118.11)
		)
		(stroke
			(width 0)
			(type default)
		)
	)
	(wire
		(pts
			(xy 132.08 86.36) (xy 144.78 86.36)
		)
		(stroke
			(width 0)
			(type default)
		)
	)
	(wire
		(pts
			(xy 132.08 106.68) (xy 135.89 106.68)
		)
		(stroke
			(width 0)
			(type default)
		)
	)
	(wire
		(pts
			(xy 323.85 67.31) (xy 316.23 67.31)
		)
		(stroke
			(width 0)
			(type default)
		)
	)
	(wire
		(pts
			(xy 283.21 67.31) (xy 283.21 68.58)
		)
		(stroke
			(width 0)
			(type default)
		)
	)
	(wire
		(pts
			(xy 243.84 176.53) (xy 242.57 176.53)
		)
		(stroke
			(width 0)
			(type default)
		)
	)
	(wire
		(pts
			(xy 140.97 134.62) (xy 140.97 137.16)
		)
		(stroke
			(width 0)
			(type default)
		)
	)
	(wire
		(pts
			(xy 266.7 67.31) (xy 266.7 68.58)
		)
		(stroke
			(width 0)
			(type default)
		)
	)
	(wire
		(pts
			(xy 152.4 86.36) (xy 152.4 87.63)
		)
		(stroke
			(width 0)
			(type default)
		)
	)
	(wire
		(pts
			(xy 152.4 106.68) (xy 152.4 107.95)
		)
		(stroke
			(width 0)
			(type default)
		)
	)
	(wire
		(pts
			(xy 132.08 139.7) (xy 132.08 134.62)
		)
		(stroke
			(width 0)
			(type default)
		)
	)
	(wire
		(pts
			(xy 140.97 129.54) (xy 140.97 128.27)
		)
		(stroke
			(width 0)
			(type default)
		)
	)
	(wire
		(pts
			(xy 55.88 115.57) (xy 66.04 115.57)
		)
		(stroke
			(width 0)
			(type default)
		)
	)
	(polyline
		(pts
			(xy 35.56 152.4) (xy 35.56 101.6)
		)
		(stroke
			(width 0)
			(type dash)
		)
	)
	(wire
		(pts
			(xy 157.48 139.7) (xy 132.08 139.7)
		)
		(stroke
			(width 0)
			(type default)
		)
	)
	(wire
		(pts
			(xy 242.57 176.53) (xy 242.57 177.8)
		)
		(stroke
			(width 0)
			(type default)
		)
	)
	(wire
		(pts
			(xy 77.47 127) (xy 77.47 129.54)
		)
		(stroke
			(width 0)
			(type default)
		)
	)
	(wire
		(pts
			(xy 71.12 138.43) (xy 77.47 138.43)
		)
		(stroke
			(width 0)
			(type default)
		)
	)
	(wire
		(pts
			(xy 299.72 140.97) (xy 241.3 140.97)
		)
		(stroke
			(width 0)
			(type default)
		)
	)
	(wire
		(pts
			(xy 196.85 130.81) (xy 189.23 130.81)
		)
		(stroke
			(width 0)
			(type default)
		)
	)
	(wire
		(pts
			(xy 77.47 110.49) (xy 77.47 115.57)
		)
		(stroke
			(width 0)
			(type default)
		)
	)
	(wire
		(pts
			(xy 241.3 158.75) (xy 257.81 158.75)
		)
		(stroke
			(width 0)
			(type default)
		)
	)
	(wire
		(pts
			(xy 168.91 106.68) (xy 177.8 106.68)
		)
		(stroke
			(width 0)
			(type default)
		)
	)
	(wire
		(pts
			(xy 307.34 67.31) (xy 307.34 68.58)
		)
		(stroke
			(width 0)
			(type default)
		)
	)
	(wire
		(pts
			(xy 290.83 86.36) (xy 283.21 86.36)
		)
		(stroke
			(width 0)
			(type default)
		)
	)
	(wire
		(pts
			(xy 299.72 147.32) (xy 241.3 147.32)
		)
		(stroke
			(width 0)
			(type default)
		)
	)
	(wire
		(pts
			(xy 242.57 173.99) (xy 241.3 173.99)
		)
		(stroke
			(width 0)
			(type default)
		)
	)
	(wire
		(pts
			(xy 274.32 106.68) (xy 274.32 107.95)
		)
		(stroke
			(width 0)
			(type default)
		)
	)
	(wire
		(pts
			(xy 299.72 134.62) (xy 241.3 134.62)
		)
		(stroke
			(width 0)
			(type default)
		)
	)
	(wire
		(pts
			(xy 323.85 67.31) (xy 323.85 68.58)
		)
		(stroke
			(width 0)
			(type default)
		)
	)
	(wire
		(pts
			(xy 251.46 67.31) (xy 251.46 114.3)
		)
		(stroke
			(width 0)
			(type default)
		)
	)
	(wire
		(pts
			(xy 299.72 67.31) (xy 307.34 67.31)
		)
		(stroke
			(width 0)
			(type default)
		)
	)
	(wire
		(pts
			(xy 191.77 185.42) (xy 191.77 184.15)
		)
		(stroke
			(width 0)
			(type default)
		)
	)
	(wire
		(pts
			(xy 317.5 135.89) (xy 322.58 135.89)
		)
		(stroke
			(width 0)
			(type default)
		)
	)
	(wire
		(pts
			(xy 177.8 86.36) (xy 177.8 87.63)
		)
		(stroke
			(width 0)
			(type default)
		)
	)
	(wire
		(pts
			(xy 341.63 135.89) (xy 327.66 135.89)
		)
		(stroke
			(width 0)
			(type default)
		)
	)
	(wire
		(pts
			(xy 177.8 184.15) (xy 177.8 173.99)
		)
		(stroke
			(width 0)
			(type default)
		)
	)
	(wire
		(pts
			(xy 330.2 86.36) (xy 330.2 106.68)
		)
		(stroke
			(width 0)
			(type default)
		)
	)
	(wire
		(pts
			(xy 55.88 135.89) (xy 66.04 135.89)
		)
		(stroke
			(width 0)
			(type default)
		)
	)
	(wire
		(pts
			(xy 55.88 138.43) (xy 66.04 138.43)
		)
		(stroke
			(width 0)
			(type default)
		)
	)
	(wire
		(pts
			(xy 283.21 106.68) (xy 283.21 107.95)
		)
		(stroke
			(width 0)
			(type default)
		)
	)
	(wire
		(pts
			(xy 177.8 110.49) (xy 177.8 106.68)
		)
		(stroke
			(width 0)
			(type default)
		)
	)
	(wire
		(pts
			(xy 43.18 129.54) (xy 66.04 129.54)
		)
		(stroke
			(width 0)
			(type default)
		)
	)
	(wire
		(pts
			(xy 295.91 161.29) (xy 299.72 161.29)
		)
		(stroke
			(width 0)
			(type default)
		)
	)
	(wire
		(pts
			(xy 241.3 156.21) (xy 257.81 156.21)
		)
		(stroke
			(width 0)
			(type default)
		)
	)
	(wire
		(pts
			(xy 330.2 67.31) (xy 330.2 86.36)
		)
		(stroke
			(width 0)
			(type default)
		)
	)
	(wire
		(pts
			(xy 270.51 153.67) (xy 270.51 162.56)
		)
		(stroke
			(width 0)
			(type default)
		)
	)
	(wire
		(pts
			(xy 317.5 140.97) (xy 332.74 140.97)
		)
		(stroke
			(width 0)
			(type default)
		)
	)
	(wire
		(pts
			(xy 290.83 106.68) (xy 283.21 106.68)
		)
		(stroke
			(width 0)
			(type default)
		)
	)
	(wire
		(pts
			(xy 283.21 86.36) (xy 283.21 87.63)
		)
		(stroke
			(width 0)
			(type default)
		)
	)
	(wire
		(pts
			(xy 290.83 86.36) (xy 312.42 86.36)
		)
		(stroke
			(width 0)
			(type default)
		)
	)
	(wire
		(pts
			(xy 317.5 86.36) (xy 330.2 86.36)
		)
		(stroke
			(width 0)
			(type default)
		)
	)
	(wire
		(pts
			(xy 341.63 144.78) (xy 327.66 144.78)
		)
		(stroke
			(width 0)
			(type default)
		)
	)
	(wire
		(pts
			(xy 55.88 118.11) (xy 66.04 118.11)
		)
		(stroke
			(width 0)
			(type default)
		)
	)
	(wire
		(pts
			(xy 43.18 127) (xy 66.04 127)
		)
		(stroke
			(width 0)
			(type default)
		)
	)
	(wire
		(pts
			(xy 189.23 128.27) (xy 196.85 128.27)
		)
		(stroke
			(width 0)
			(type default)
		)
	)
	(wire
		(pts
			(xy 189.23 161.29) (xy 196.85 161.29)
		)
		(stroke
			(width 0)
			(type default)
		)
	)
	(wire
		(pts
			(xy 196.85 171.45) (xy 177.8 171.45)
		)
		(stroke
			(width 0)
			(type default)
		)
	)
	(wire
		(pts
			(xy 71.12 129.54) (xy 77.47 129.54)
		)
		(stroke
			(width 0)
			(type default)
		)
	)
	(wire
		(pts
			(xy 77.47 129.54) (xy 77.47 132.08)
		)
		(stroke
			(width 0)
			(type default)
		)
	)
	(wire
		(pts
			(xy 55.88 120.65) (xy 66.04 120.65)
		)
		(stroke
			(width 0)
			(type default)
		)
	)
	(wire
		(pts
			(xy 140.97 128.27) (xy 132.08 128.27)
		)
		(stroke
			(width 0)
			(type default)
		)
	)
	(wire
		(pts
			(xy 55.88 123.19) (xy 66.04 123.19)
		)
		(stroke
			(width 0)
			(type default)
		)
	)
	(wire
		(pts
			(xy 279.4 156.21) (xy 279.4 162.56)
		)
		(stroke
			(width 0)
			(type default)
		)
	)
	(wire
		(pts
			(xy 241.3 114.3) (xy 251.46 114.3)
		)
		(stroke
			(width 0)
			(type default)
		)
	)
	(wire
		(pts
			(xy 191.77 173.99) (xy 196.85 173.99)
		)
		(stroke
			(width 0)
			(type default)
		)
	)
	(wire
		(pts
			(xy 144.78 86.36) (xy 144.78 87.63)
		)
		(stroke
			(width 0)
			(type default)
		)
	)
	(wire
		(pts
			(xy 241.3 128.27) (xy 299.72 128.27)
		)
		(stroke
			(width 0)
			(type default)
		)
	)
	(wire
		(pts
			(xy 242.57 171.45) (xy 241.3 171.45)
		)
		(stroke
			(width 0)
			(type default)
		)
	)
	(wire
		(pts
			(xy 157.48 137.16) (xy 140.97 137.16)
		)
		(stroke
			(width 0)
			(type default)
		)
	)
	(wire
		(pts
			(xy 185.42 189.23) (xy 185.42 190.5)
		)
		(stroke
			(width 0)
			(type default)
		)
	)
	(wire
		(pts
			(xy 152.4 106.68) (xy 160.02 106.68)
		)
		(stroke
			(width 0)
			(type default)
		)
	)
	(wire
		(pts
			(xy 274.32 86.36) (xy 274.32 87.63)
		)
		(stroke
			(width 0)
			(type default)
		)
	)
	(wire
		(pts
			(xy 168.91 86.36) (xy 177.8 86.36)
		)
		(stroke
			(width 0)
			(type default)
		)
	)
	(wire
		(pts
			(xy 274.32 86.36) (xy 283.21 86.36)
		)
		(stroke
			(width 0)
			(type default)
		)
	)
	(wire
		(pts
			(xy 196.85 158.75) (xy 189.23 158.75)
		)
		(stroke
			(width 0)
			(type default)
		)
	)
	(wire
		(pts
			(xy 77.47 135.89) (xy 77.47 138.43)
		)
		(stroke
			(width 0)
			(type default)
		)
	)
	(wire
		(pts
			(xy 257.81 67.31) (xy 257.81 68.58)
		)
		(stroke
			(width 0)
			(type default)
		)
	)
	(wire
		(pts
			(xy 71.12 120.65) (xy 77.47 120.65)
		)
		(stroke
			(width 0)
			(type default)
		)
	)
	(wire
		(pts
			(xy 242.57 171.45) (xy 242.57 173.99)
		)
		(stroke
			(width 0)
			(type default)
		)
	)
	(wire
		(pts
			(xy 196.85 147.32) (xy 189.23 147.32)
		)
		(stroke
			(width 0)
			(type default)
		)
	)
	(wire
		(pts
			(xy 161.29 86.36) (xy 161.29 87.63)
		)
		(stroke
			(width 0)
			(type default)
		)
	)
	(wire
		(pts
			(xy 241.3 120.65) (xy 266.7 120.65)
		)
		(stroke
			(width 0)
			(type default)
		)
	)
	(wire
		(pts
			(xy 77.47 132.08) (xy 77.47 135.89)
		)
		(stroke
			(width 0)
			(type default)
		)
	)
	(wire
		(pts
			(xy 287.02 158.75) (xy 287.02 162.56)
		)
		(stroke
			(width 0)
			(type default)
		)
	)
	(wire
		(pts
			(xy 189.23 184.15) (xy 191.77 184.15)
		)
		(stroke
			(width 0)
			(type default)
		)
	)
	(wire
		(pts
			(xy 189.23 134.62) (xy 196.85 134.62)
		)
		(stroke
			(width 0)
			(type default)
		)
	)
	(wire
		(pts
			(xy 161.29 86.36) (xy 152.4 86.36)
		)
		(stroke
			(width 0)
			(type default)
		)
	)
	(wire
		(pts
			(xy 196.85 153.67) (xy 189.23 153.67)
		)
		(stroke
			(width 0)
			(type default)
		)
	)
	(wire
		(pts
			(xy 130.81 128.27) (xy 132.08 128.27)
		)
		(stroke
			(width 0)
			(type default)
		)
	)
	(wire
		(pts
			(xy 177.8 118.11) (xy 177.8 110.49)
		)
		(stroke
			(width 0)
			(type default)
		)
	)
	(wire
		(pts
			(xy 177.8 171.45) (xy 177.8 173.99)
		)
		(stroke
			(width 0)
			(type default)
		)
	)
	(wire
		(pts
			(xy 290.83 67.31) (xy 283.21 67.31)
		)
		(stroke
			(width 0)
			(type default)
		)
	)
	(wire
		(pts
			(xy 71.12 127) (xy 77.47 127)
		)
		(stroke
			(width 0)
			(type default)
		)
	)
	(wire
		(pts
			(xy 181.61 184.15) (xy 177.8 184.15)
		)
		(stroke
			(width 0)
			(type default)
		)
	)
	(wire
		(pts
			(xy 71.12 123.19) (xy 77.47 123.19)
		)
		(stroke
			(width 0)
			(type default)
		)
	)
	(polyline
		(pts
			(xy 99.06 101.6) (xy 35.56 101.6)
		)
		(stroke
			(width 0)
			(type dash)
		)
	)
	(wire
		(pts
			(xy 317.5 158.75) (xy 320.04 158.75)
		)
		(stroke
			(width 0)
			(type default)
		)
	)
	(polyline
		(pts
			(xy 99.06 152.4) (xy 35.56 152.4)
		)
		(stroke
			(width 0)
			(type dash)
		)
	)
	(wire
		(pts
			(xy 251.46 67.31) (xy 257.81 67.31)
		)
		(stroke
			(width 0)
			(type default)
		)
	)
	(wire
		(pts
			(xy 241.3 130.81) (xy 299.72 130.81)
		)
		(stroke
			(width 0)
			(type default)
		)
	)
	(wire
		(pts
			(xy 191.77 173.99) (xy 191.77 184.15)
		)
		(stroke
			(width 0)
			(type default)
		)
	)
	(wire
		(pts
			(xy 290.83 106.68) (xy 290.83 107.95)
		)
		(stroke
			(width 0)
			(type default)
		)
	)
	(wire
		(pts
			(xy 266.7 67.31) (xy 257.81 67.31)
		)
		(stroke
			(width 0)
			(type default)
		)
	)
	(wire
		(pts
			(xy 81.28 110.49) (xy 77.47 110.49)
		)
		(stroke
			(width 0)
			(type default)
		)
	)
	(wire
		(pts
			(xy 177.8 86.36) (xy 184.15 86.36)
		)
		(stroke
			(width 0)
			(type default)
		)
	)
	(wire
		(pts
			(xy 77.47 123.19) (xy 77.47 127)
		)
		(stroke
			(width 0)
			(type default)
		)
	)
	(wire
		(pts
			(xy 274.32 67.31) (xy 274.32 68.58)
		)
		(stroke
			(width 0)
			(type default)
		)
	)
	(wire
		(pts
			(xy 299.72 67.31) (xy 290.83 67.31)
		)
		(stroke
			(width 0)
			(type default)
		)
	)
	(wire
		(pts
			(xy 317.5 144.78) (xy 322.58 144.78)
		)
		(stroke
			(width 0)
			(type default)
		)
	)
	(wire
		(pts
			(xy 283.21 67.31) (xy 274.32 67.31)
		)
		(stroke
			(width 0)
			(type default)
		)
	)
	(wire
		(pts
			(xy 299.72 158.75) (xy 287.02 158.75)
		)
		(stroke
			(width 0)
			(type default)
		)
	)
	(wire
		(pts
			(xy 196.85 142.24) (xy 189.23 142.24)
		)
		(stroke
			(width 0)
			(type default)
		)
	)
	(wire
		(pts
			(xy 316.23 67.31) (xy 307.34 67.31)
		)
		(stroke
			(width 0)
			(type default)
		)
	)
	(wire
		(pts
			(xy 259.08 86.36) (xy 266.7 86.36)
		)
		(stroke
			(width 0)
			(type default)
		)
	)
	(wire
		(pts
			(xy 71.12 115.57) (xy 77.47 115.57)
		)
		(stroke
			(width 0)
			(type default)
		)
	)
	(wire
		(pts
			(xy 299.72 153.67) (xy 270.51 153.67)
		)
		(stroke
			(width 0)
			(type default)
		)
	)
	(wire
		(pts
			(xy 299.72 67.31) (xy 299.72 68.58)
		)
		(stroke
			(width 0)
			(type default)
		)
	)
	(wire
		(pts
			(xy 132.08 86.36) (xy 132.08 106.68)
		)
		(stroke
			(width 0)
			(type default)
		)
	)
	(label "ETH3_P"
		(at 257.81 140.97 180)
		(effects
			(font
				(size 1.27 1.27)
			)
			(justify right bottom)
		)
	)
	(label "ETH1_N"
		(at 257.81 130.81 180)
		(effects
			(font
				(size 1.27 1.27)
			)
			(justify right bottom)
		)
	)
	(label "ETH2_N"
		(at 257.81 137.16 180)
		(effects
			(font
				(size 1.27 1.27)
			)
			(justify right bottom)
		)
	)
	(label "AVDDL"
		(at 242.57 118.11 0)
		(effects
			(font
				(size 1.27 1.27)
			)
			(justify left bottom)
		)
	)
	(label "ETH_LED2"
		(at 341.63 144.78 180)
		(effects
			(font
				(size 1.27 1.27)
			)
			(justify right bottom)
		)
	)
	(label "ETH4_P"
		(at 257.81 147.32 180)
		(effects
			(font
				(size 1.27 1.27)
			)
			(justify right bottom)
		)
	)
	(label "ETH_LED2"
		(at 257.81 158.75 180)
		(effects
			(font
				(size 1.27 1.27)
			)
			(justify right bottom)
		)
	)
	(label "ETH4_N"
		(at 257.81 149.86 180)
		(effects
			(font
				(size 1.27 1.27)
			)
			(justify right bottom)
		)
	)
	(label "ETH_LED1"
		(at 43.18 127 0)
		(effects
			(font
				(size 1.27 1.27)
			)
			(justify left bottom)
		)
	)
	(label "ETH_LED2"
		(at 43.18 129.54 0)
		(effects
			(font
				(size 1.27 1.27)
			)
			(justify left bottom)
		)
	)
	(label "ETH_LED1"
		(at 341.63 135.89 180)
		(effects
			(font
				(size 1.27 1.27)
			)
			(justify right bottom)
		)
	)
	(label "AVDDH"
		(at 189.23 118.11 0)
		(effects
			(font
				(size 1.27 1.27)
			)
			(justify left bottom)
		)
	)
	(label "ETH1_P"
		(at 257.81 128.27 180)
		(effects
			(font
				(size 1.27 1.27)
			)
			(justify right bottom)
		)
	)
	(label "ETH3_N"
		(at 257.81 143.51 180)
		(effects
			(font
				(size 1.27 1.27)
			)
			(justify right bottom)
		)
	)
	(label "AVDDL_PLL"
		(at 242.57 120.65 0)
		(effects
			(font
				(size 1.27 1.27)
			)
			(justify left bottom)
		)
	)
	(label "ETH_MDIO"
		(at 157.48 139.7 180)
		(effects
			(font
				(size 1.27 1.27)
			)
			(justify right bottom)
		)
	)
	(label "ETH2_P"
		(at 257.81 134.62 180)
		(effects
			(font
				(size 1.27 1.27)
			)
			(justify right bottom)
		)
	)
	(label "ETH_LED1"
		(at 257.81 156.21 180)
		(effects
			(font
				(size 1.27 1.27)
			)
			(justify right bottom)
		)
	)
	(label "ETH_~{RESET}"
		(at 157.48 137.16 180)
		(effects
			(font
				(size 1.27 1.27)
			)
			(justify right bottom)
		)
	)
	(global_label "RGMII_TXD3"
		(shape input)
		(at 189.23 144.78 180)
		(fields_autoplaced yes)
		(effects
			(font
				(size 1.27 1.27)
			)
			(justify right)
		)
		(property "Intersheetrefs" "${INTERSHEET_REFS}"
			(at 34.29 20.32 0)
			(effects
				(font
					(size 1.27 1.27)
				)
				(hide yes)
			)
		)
	)
	(global_label "ETH_INT_N"
		(shape output)
		(at 189.23 124.46 180)
		(fields_autoplaced yes)
		(effects
			(font
				(size 1.27 1.27)
			)
			(justify right)
		)
		(property "Intersheetrefs" "${INTERSHEET_REFS}"
			(at 34.925 -30.48 0)
			(effects
				(font
					(size 1.27 1.27)
				)
				(hide yes)
			)
		)
	)
	(global_label "RGMII_TXD2"
		(shape input)
		(at 189.23 142.24 180)
		(fields_autoplaced yes)
		(effects
			(font
				(size 1.27 1.27)
			)
			(justify right)
		)
		(property "Intersheetrefs" "${INTERSHEET_REFS}"
			(at 34.29 20.32 0)
			(effects
				(font
					(size 1.27 1.27)
				)
				(hide yes)
			)
		)
	)
	(global_label "RGMII_TXD1"
		(shape input)
		(at 189.23 139.7 180)
		(fields_autoplaced yes)
		(effects
			(font
				(size 1.27 1.27)
			)
			(justify right)
		)
		(property "Intersheetrefs" "${INTERSHEET_REFS}"
			(at 34.29 20.32 0)
			(effects
				(font
					(size 1.27 1.27)
				)
				(hide yes)
			)
		)
	)
	(global_label "ETH_MDC"
		(shape input)
		(at 189.23 128.27 180)
		(fields_autoplaced yes)
		(effects
			(font
				(size 1.27 1.27)
			)
			(justify right)
		)
		(property "Intersheetrefs" "${INTERSHEET_REFS}"
			(at 34.29 21.59 0)
			(effects
				(font
					(size 1.27 1.27)
				)
				(hide yes)
			)
		)
	)
	(global_label "ETH_MDIO"
		(shape bidirectional)
		(at 189.23 130.81 180)
		(fields_autoplaced yes)
		(effects
			(font
				(size 1.27 1.27)
			)
			(justify right)
		)
		(property "Intersheetrefs" "${INTERSHEET_REFS}"
			(at 34.29 21.59 0)
			(effects
				(font
					(size 1.27 1.27)
				)
				(hide yes)
			)
		)
	)
	(global_label "RGMII_RXD1"
		(shape passive)
		(at 55.88 120.65 180)
		(fields_autoplaced yes)
		(effects
			(font
				(size 1.27 1.27)
			)
			(justify right)
		)
		(property "Intersheetrefs" "${INTERSHEET_REFS}"
			(at -146.05 -101.6 0)
			(effects
				(font
					(size 1.27 1.27)
				)
				(justify right)
				(hide yes)
			)
		)
	)
	(global_label "RGMII_RX_CLK"
		(shape passive)
		(at 55.88 132.08 180)
		(fields_autoplaced yes)
		(effects
			(font
				(size 1.27 1.27)
			)
			(justify right)
		)
		(property "Intersheetrefs" "${INTERSHEET_REFS}"
			(at -146.05 -100.33 0)
			(effects
				(font
					(size 1.27 1.27)
				)
				(justify right)
				(hide yes)
			)
		)
	)
	(global_label "RGMII_RXD0"
		(shape passive)
		(at 55.88 123.19 180)
		(fields_autoplaced yes)
		(effects
			(font
				(size 1.27 1.27)
			)
			(justify right)
		)
		(property "Intersheetrefs" "${INTERSHEET_REFS}"
			(at -146.05 -96.52 0)
			(effects
				(font
					(size 1.27 1.27)
				)
				(justify right)
				(hide yes)
			)
		)
	)
	(global_label "VCC3V3"
		(shape input)
		(at 332.74 132.08 0)
		(fields_autoplaced yes)
		(effects
			(font
				(size 1.27 1.27)
			)
			(justify left)
		)
		(property "Intersheetrefs" "${INTERSHEET_REFS}"
			(at 645.795 -3.81 0)
			(effects
				(font
					(size 1.27 1.27)
				)
				(justify left)
				(hide yes)
			)
		)
	)
	(global_label "VCC1V2"
		(shape input)
		(at 332.74 67.31 0)
		(fields_autoplaced yes)
		(effects
			(font
				(size 1.27 1.27)
			)
			(justify left)
		)
		(property "Intersheetrefs" "${INTERSHEET_REFS}"
			(at 382.27 108.585 0)
			(effects
				(font
					(size 1.27 1.27)
				)
				(justify left)
				(hide yes)
			)
		)
	)
	(global_label "RGMII_RX_CLK"
		(shape output)
		(at 189.23 163.83 180)
		(fields_autoplaced yes)
		(effects
			(font
				(size 1.27 1.27)
			)
			(justify right)
		)
		(property "Intersheetrefs" "${INTERSHEET_REFS}"
			(at 34.29 19.05 0)
			(effects
				(font
					(size 1.27 1.27)
				)
				(hide yes)
			)
		)
	)
	(global_label "RGMII_REF_CLK"
		(shape passive)
		(at 55.88 138.43 180)
		(fields_autoplaced yes)
		(effects
			(font
				(size 1.27 1.27)
			)
			(justify right)
		)
		(property "Intersheetrefs" "${INTERSHEET_REFS}"
			(at -146.05 -96.52 0)
			(effects
				(font
					(size 1.27 1.27)
				)
				(justify right)
				(hide yes)
			)
		)
	)
	(global_label "VCC3V3"
		(shape input)
		(at 81.28 110.49 0)
		(fields_autoplaced yes)
		(effects
			(font
				(size 1.27 1.27)
			)
			(justify left)
		)
		(property "Intersheetrefs" "${INTERSHEET_REFS}"
			(at 297.18 -116.205 90)
			(effects
				(font
					(size 1.27 1.27)
				)
				(justify left)
				(hide yes)
			)
		)
	)
	(global_label "RGMII_RXD3"
		(shape output)
		(at 189.23 161.29 180)
		(fields_autoplaced yes)
		(effects
			(font
				(size 1.27 1.27)
			)
			(justify right)
		)
		(property "Intersheetrefs" "${INTERSHEET_REFS}"
			(at 34.29 19.05 0)
			(effects
				(font
					(size 1.27 1.27)
				)
				(hide yes)
			)
		)
	)
	(global_label "RGMII_RX_DV"
		(shape passive)
		(at 55.88 135.89 180)
		(fields_autoplaced yes)
		(effects
			(font
				(size 1.27 1.27)
			)
			(justify right)
		)
		(property "Intersheetrefs" "${INTERSHEET_REFS}"
			(at -146.05 -93.98 0)
			(effects
				(font
					(size 1.27 1.27)
				)
				(justify right)
				(hide yes)
			)
		)
	)
	(global_label "VCC3V3"
		(shape input)
		(at 130.81 128.27 180)
		(fields_autoplaced yes)
		(effects
			(font
				(size 1.27 1.27)
			)
			(justify right)
		)
		(property "Intersheetrefs" "${INTERSHEET_REFS}"
			(at -85.09 354.965 90)
			(effects
				(font
					(size 1.27 1.27)
				)
				(justify right)
				(hide yes)
			)
		)
	)
	(global_label "RGMII_REF_CLK"
		(shape output)
		(at 189.23 167.64 180)
		(fields_autoplaced yes)
		(effects
			(font
				(size 1.27 1.27)
			)
			(justify right)
		)
		(property "Intersheetrefs" "${INTERSHEET_REFS}"
			(at 34.925 7.62 0)
			(effects
				(font
					(size 1.27 1.27)
				)
				(hide yes)
			)
		)
	)
	(global_label "RGMII_RXD3"
		(shape passive)
		(at 55.88 115.57 180)
		(fields_autoplaced yes)
		(effects
			(font
				(size 1.27 1.27)
			)
			(justify right)
		)
		(property "Intersheetrefs" "${INTERSHEET_REFS}"
			(at -146.05 -111.76 0)
			(effects
				(font
					(size 1.27 1.27)
				)
				(justify right)
				(hide yes)
			)
		)
	)
	(global_label "RGMII_TX_DV"
		(shape input)
		(at 189.23 134.62 180)
		(fields_autoplaced yes)
		(effects
			(font
				(size 1.27 1.27)
			)
			(justify right)
		)
		(property "Intersheetrefs" "${INTERSHEET_REFS}"
			(at 34.29 20.32 0)
			(effects
				(font
					(size 1.27 1.27)
				)
				(hide yes)
			)
		)
	)
	(global_label "RGMII_TXD0"
		(shape input)
		(at 189.23 137.16 180)
		(fields_autoplaced yes)
		(effects
			(font
				(size 1.27 1.27)
			)
			(justify right)
		)
		(property "Intersheetrefs" "${INTERSHEET_REFS}"
			(at 34.29 20.32 0)
			(effects
				(font
					(size 1.27 1.27)
				)
				(hide yes)
			)
		)
	)
	(global_label "ETH_~{RESET}"
		(shape input)
		(at 189.23 121.92 180)
		(fields_autoplaced yes)
		(effects
			(font
				(size 1.27 1.27)
			)
			(justify right)
		)
		(property "Intersheetrefs" "${INTERSHEET_REFS}"
			(at 34.925 -41.91 0)
			(effects
				(font
					(size 1.27 1.27)
				)
				(hide yes)
			)
		)
	)
	(global_label "RGMII_RX_DV"
		(shape output)
		(at 189.23 151.13 180)
		(fields_autoplaced yes)
		(effects
			(font
				(size 1.27 1.27)
			)
			(justify right)
		)
		(property "Intersheetrefs" "${INTERSHEET_REFS}"
			(at 34.29 19.05 0)
			(effects
				(font
					(size 1.27 1.27)
				)
				(hide yes)
			)
		)
	)
	(global_label "RGMII_TX_CLK"
		(shape input)
		(at 189.23 147.32 180)
		(fields_autoplaced yes)
		(effects
			(font
				(size 1.27 1.27)
			)
			(justify right)
		)
		(property "Intersheetrefs" "${INTERSHEET_REFS}"
			(at 34.29 20.32 0)
			(effects
				(font
					(size 1.27 1.27)
				)
				(hide yes)
			)
		)
	)
	(global_label "RGMII_RXD2"
		(shape passive)
		(at 55.88 118.11 180)
		(fields_autoplaced yes)
		(effects
			(font
				(size 1.27 1.27)
			)
			(justify right)
		)
		(property "Intersheetrefs" "${INTERSHEET_REFS}"
			(at -146.05 -106.68 0)
			(effects
				(font
					(size 1.27 1.27)
				)
				(justify right)
				(hide yes)
			)
		)
	)
	(global_label "VCC3V3"
		(shape input)
		(at 332.74 140.97 0)
		(fields_autoplaced yes)
		(effects
			(font
				(size 1.27 1.27)
			)
			(justify left)
		)
		(property "Intersheetrefs" "${INTERSHEET_REFS}"
			(at 645.795 -4.445 0)
			(effects
				(font
					(size 1.27 1.27)
				)
				(justify left)
				(hide yes)
			)
		)
	)
	(global_label "RGMII_RXD1"
		(shape output)
		(at 189.23 156.21 180)
		(fields_autoplaced yes)
		(effects
			(font
				(size 1.27 1.27)
			)
			(justify right)
		)
		(property "Intersheetrefs" "${INTERSHEET_REFS}"
			(at 34.29 19.05 0)
			(effects
				(font
					(size 1.27 1.27)
				)
				(hide yes)
			)
		)
	)
	(global_label "RGMII_RXD0"
		(shape output)
		(at 189.23 153.67 180)
		(fields_autoplaced yes)
		(effects
			(font
				(size 1.27 1.27)
			)
			(justify right)
		)
		(property "Intersheetrefs" "${INTERSHEET_REFS}"
			(at 34.29 19.05 0)
			(effects
				(font
					(size 1.27 1.27)
				)
				(hide yes)
			)
		)
	)
	(global_label "VCC3V3"
		(shape input)
		(at 130.81 86.36 180)
		(fields_autoplaced yes)
		(effects
			(font
				(size 1.27 1.27)
			)
			(justify right)
		)
		(property "Intersheetrefs" "${INTERSHEET_REFS}"
			(at -1.905 142.875 0)
			(effects
				(font
					(size 1.27 1.27)
				)
				(hide yes)
			)
		)
	)
	(global_label "RGMII_RXD2"
		(shape output)
		(at 189.23 158.75 180)
		(fields_autoplaced yes)
		(effects
			(font
				(size 1.27 1.27)
			)
			(justify right)
		)
		(property "Intersheetrefs" "${INTERSHEET_REFS}"
			(at 34.29 19.05 0)
			(effects
				(font
					(size 1.27 1.27)
				)
				(hide yes)
			)
		)
	)
	(symbol
		(lib_id "antmicroResistors0402:R_220R_0402")
		(at 322.58 144.78 0)
		(unit 1)
		(exclude_from_sim no)
		(in_bom yes)
		(on_board yes)
		(dnp no)
		(property "Reference" "R166"
			(at 325.12 142.24 0)
			(effects
				(font
					(size 1.27 1.27)
				)
			)
		)
		(property "Value" "R_220R_0402"
			(at 342.9 157.48 0)
			(effects
				(font
					(size 1.27 1.27)
					(thickness 0.15)
				)
				(justify left bottom)
				(hide yes)
			)
		)
		(property "Footprint" "antmicro-footprints:R_0402_1005Metric"
			(at 342.9 160.02 0)
			(effects
				(font
					(size 1.27 1.27)
					(thickness 0.15)
				)
				(justify left bottom)
				(hide yes)
			)
		)
		(property "Datasheet" "https://www.bourns.com/docs/product-datasheets/cr.pdf"
			(at 342.9 162.56 0)
			(effects
				(font
					(size 1.27 1.27)
					(thickness 0.15)
				)
				(justify left bottom)
				(hide yes)
			)
		)
		(property "Description" "SMD Chip Resistor, 220 ohm, ± 1%, 62.5 mW, 0402 [1005 Metric], Thick Film, General Purpose"
			(at 322.58 144.78 0)
			(effects
				(font
					(size 1.27 1.27)
				)
				(hide yes)
			)
		)
		(property "Manufacturer" "Bourns"
			(at 342.9 167.64 0)
			(effects
				(font
					(size 1.27 1.27)
					(thickness 0.15)
				)
				(justify left bottom)
				(hide yes)
			)
		)
		(property "MPN" "CR0402-FX-2200GLF"
			(at 342.9 165.1 0)
			(effects
				(font
					(size 1.27 1.27)
					(thickness 0.15)
				)
				(justify left bottom)
				(hide yes)
			)
		)
		(property "Val" "220R"
			(at 325.12 147.32 0)
			(effects
				(font
					(size 1.27 1.27)
					(thickness 0.15)
				)
			)
		)
		(property "License" "Apache-2.0"
			(at 342.9 170.18 0)
			(effects
				(font
					(size 1.27 1.27)
					(thickness 0.15)
				)
				(justify left bottom)
				(hide yes)
			)
		)
		(property "Author" "Antmicro"
			(at 342.9 172.72 0)
			(effects
				(font
					(size 1.27 1.27)
					(thickness 0.15)
				)
				(justify left bottom)
				(hide yes)
			)
		)
		(property "Tolerance" "1%"
			(at 342.9 154.94 0)
			(effects
				(font
					(size 1.27 1.27)
				)
				(justify left bottom)
				(hide yes)
			)
		)
		(pin "1"
		)
		(pin "2"
		)
		(instances
			(project "artix-dc-scm"
				(path ""
					(reference "R166")
					(unit 1)
				)
			)
		)
	)
	(symbol
		(lib_id "antmicroResistors0402:R_220R_0402")
		(at 322.58 135.89 0)
		(unit 1)
		(exclude_from_sim no)
		(in_bom yes)
		(on_board yes)
		(dnp no)
		(property "Reference" "R165"
			(at 325.12 133.35 0)
			(effects
				(font
					(size 1.27 1.27)
				)
			)
		)
		(property "Value" "R_220R_0402"
			(at 342.9 148.59 0)
			(effects
				(font
					(size 1.27 1.27)
					(thickness 0.15)
				)
				(justify left bottom)
				(hide yes)
			)
		)
		(property "Footprint" "antmicro-footprints:R_0402_1005Metric"
			(at 342.9 151.13 0)
			(effects
				(font
					(size 1.27 1.27)
					(thickness 0.15)
				)
				(justify left bottom)
				(hide yes)
			)
		)
		(property "Datasheet" "https://www.bourns.com/docs/product-datasheets/cr.pdf"
			(at 342.9 153.67 0)
			(effects
				(font
					(size 1.27 1.27)
					(thickness 0.15)
				)
				(justify left bottom)
				(hide yes)
			)
		)
		(property "Description" "SMD Chip Resistor, 220 ohm, ± 1%, 62.5 mW, 0402 [1005 Metric], Thick Film, General Purpose"
			(at 322.58 135.89 0)
			(effects
				(font
					(size 1.27 1.27)
				)
				(hide yes)
			)
		)
		(property "Manufacturer" "Bourns"
			(at 342.9 158.75 0)
			(effects
				(font
					(size 1.27 1.27)
					(thickness 0.15)
				)
				(justify left bottom)
				(hide yes)
			)
		)
		(property "MPN" "CR0402-FX-2200GLF"
			(at 342.9 156.21 0)
			(effects
				(font
					(size 1.27 1.27)
					(thickness 0.15)
				)
				(justify left bottom)
				(hide yes)
			)
		)
		(property "Val" "220R"
			(at 325.12 138.43 0)
			(effects
				(font
					(size 1.27 1.27)
					(thickness 0.15)
				)
			)
		)
		(property "License" "Apache-2.0"
			(at 342.9 161.29 0)
			(effects
				(font
					(size 1.27 1.27)
					(thickness 0.15)
				)
				(justify left bottom)
				(hide yes)
			)
		)
		(property "Author" "Antmicro"
			(at 342.9 163.83 0)
			(effects
				(font
					(size 1.27 1.27)
					(thickness 0.15)
				)
				(justify left bottom)
				(hide yes)
			)
		)
		(property "Tolerance" "1%"
			(at 342.9 146.05 0)
			(effects
				(font
					(size 1.27 1.27)
				)
				(justify left bottom)
				(hide yes)
			)
		)
		(pin "1"
		)
		(pin "2"
		)
		(instances
			(project "artix-dc-scm"
				(path ""
					(reference "R165")
					(unit 1)
				)
			)
		)
	)
	(symbol
		(lib_id "antmicroResistors0402:R_10k2_0402")
		(at 66.04 123.19 0)
		(unit 1)
		(exclude_from_sim no)
		(in_bom yes)
		(on_board yes)
		(dnp no)
		(property "Reference" "R127"
			(at 76.2 121.92 0)
			(effects
				(font
					(size 1.27 1.27)
				)
				(justify right)
			)
		)
		(property "Value" "R_10k2_0402"
			(at 86.36 135.89 0)
			(effects
				(font
					(size 1.27 1.27)
					(thickness 0.15)
				)
				(justify left bottom)
				(hide yes)
			)
		)
		(property "Footprint" "antmicro-footprints:R_0402_1005Metric"
			(at 86.36 138.43 0)
			(effects
				(font
					(size 1.27 1.27)
					(thickness 0.15)
				)
				(justify left bottom)
				(hide yes)
			)
		)
		(property "Datasheet" "https://www.bourns.com/docs/product-datasheets/cr.pdf"
			(at 86.36 140.97 0)
			(effects
				(font
					(size 1.27 1.27)
					(thickness 0.15)
				)
				(justify left bottom)
				(hide yes)
			)
		)
		(property "Description" "SMD Chip Resistor"
			(at 66.04 123.19 0)
			(effects
				(font
					(size 1.27 1.27)
				)
				(hide yes)
			)
		)
		(property "Manufacturer" "Bourns"
			(at 86.36 146.05 0)
			(effects
				(font
					(size 1.27 1.27)
					(thickness 0.15)
				)
				(justify left bottom)
				(hide yes)
			)
		)
		(property "MPN" "CR0402-FX-1022GLF"
			(at 86.36 143.51 0)
			(effects
				(font
					(size 1.27 1.27)
					(thickness 0.15)
				)
				(justify left bottom)
				(hide yes)
			)
		)
		(property "Val" "10k2"
			(at 60.96 123.19 0)
			(effects
				(font
					(size 1.27 1.27)
					(thickness 0.15)
				)
				(justify left bottom)
			)
		)
		(property "License" "Apache-2.0"
			(at 86.36 148.59 0)
			(effects
				(font
					(size 1.27 1.27)
					(thickness 0.15)
				)
				(justify left bottom)
				(hide yes)
			)
		)
		(property "Author" "Antmicro"
			(at 86.36 151.13 0)
			(effects
				(font
					(size 1.27 1.27)
					(thickness 0.15)
				)
				(justify left bottom)
				(hide yes)
			)
		)
		(property "Tolerance" "1%"
			(at 86.36 133.35 0)
			(effects
				(font
					(size 1.27 1.27)
				)
				(justify left bottom)
				(hide yes)
			)
		)
		(pin "1"
		)
		(pin "2"
		)
		(instances
			(project "artix-dc-scm"
				(path ""
					(reference "R127")
					(unit 1)
				)
			)
		)
	)
	(symbol
		(lib_id "antmicroResistors0402:R_10k2_0402")
		(at 66.04 120.65 0)
		(unit 1)
		(exclude_from_sim no)
		(in_bom yes)
		(on_board yes)
		(dnp no)
		(property "Reference" "R148"
			(at 76.2 119.38 0)
			(effects
				(font
					(size 1.27 1.27)
				)
				(justify right)
			)
		)
		(property "Value" "R_10k2_0402"
			(at 86.36 133.35 0)
			(effects
				(font
					(size 1.27 1.27)
					(thickness 0.15)
				)
				(justify left bottom)
				(hide yes)
			)
		)
		(property "Footprint" "antmicro-footprints:R_0402_1005Metric"
			(at 86.36 135.89 0)
			(effects
				(font
					(size 1.27 1.27)
					(thickness 0.15)
				)
				(justify left bottom)
				(hide yes)
			)
		)
		(property "Datasheet" "https://www.bourns.com/docs/product-datasheets/cr.pdf"
			(at 86.36 138.43 0)
			(effects
				(font
					(size 1.27 1.27)
					(thickness 0.15)
				)
				(justify left bottom)
				(hide yes)
			)
		)
		(property "Description" "SMD Chip Resistor"
			(at 66.04 120.65 0)
			(effects
				(font
					(size 1.27 1.27)
				)
				(hide yes)
			)
		)
		(property "Manufacturer" "Bourns"
			(at 86.36 143.51 0)
			(effects
				(font
					(size 1.27 1.27)
					(thickness 0.15)
				)
				(justify left bottom)
				(hide yes)
			)
		)
		(property "MPN" "CR0402-FX-1022GLF"
			(at 86.36 140.97 0)
			(effects
				(font
					(size 1.27 1.27)
					(thickness 0.15)
				)
				(justify left bottom)
				(hide yes)
			)
		)
		(property "Val" "10k2"
			(at 60.96 120.65 0)
			(effects
				(font
					(size 1.27 1.27)
					(thickness 0.15)
				)
				(justify left bottom)
			)
		)
		(property "License" "Apache-2.0"
			(at 86.36 146.05 0)
			(effects
				(font
					(size 1.27 1.27)
					(thickness 0.15)
				)
				(justify left bottom)
				(hide yes)
			)
		)
		(property "Author" "Antmicro"
			(at 86.36 148.59 0)
			(effects
				(font
					(size 1.27 1.27)
					(thickness 0.15)
				)
				(justify left bottom)
				(hide yes)
			)
		)
		(property "Tolerance" "1%"
			(at 86.36 130.81 0)
			(effects
				(font
					(size 1.27 1.27)
				)
				(justify left bottom)
				(hide yes)
			)
		)
		(pin "1"
		)
		(pin "2"
		)
		(instances
			(project "artix-dc-scm"
				(path ""
					(reference "R148")
					(unit 1)
				)
			)
		)
	)
	(symbol
		(lib_id "antmicroResistors0402:R_10k2_0402")
		(at 66.04 118.11 0)
		(unit 1)
		(exclude_from_sim no)
		(in_bom yes)
		(on_board yes)
		(dnp no)
		(property "Reference" "R149"
			(at 76.2 116.84 0)
			(effects
				(font
					(size 1.27 1.27)
				)
				(justify right)
			)
		)
		(property "Value" "R_10k2_0402"
			(at 86.36 130.81 0)
			(effects
				(font
					(size 1.27 1.27)
					(thickness 0.15)
				)
				(justify left bottom)
				(hide yes)
			)
		)
		(property "Footprint" "antmicro-footprints:R_0402_1005Metric"
			(at 86.36 133.35 0)
			(effects
				(font
					(size 1.27 1.27)
					(thickness 0.15)
				)
				(justify left bottom)
				(hide yes)
			)
		)
		(property "Datasheet" "https://www.bourns.com/docs/product-datasheets/cr.pdf"
			(at 86.36 135.89 0)
			(effects
				(font
					(size 1.27 1.27)
					(thickness 0.15)
				)
				(justify left bottom)
				(hide yes)
			)
		)
		(property "Description" "SMD Chip Resistor"
			(at 66.04 118.11 0)
			(effects
				(font
					(size 1.27 1.27)
				)
				(hide yes)
			)
		)
		(property "Manufacturer" "Bourns"
			(at 86.36 140.97 0)
			(effects
				(font
					(size 1.27 1.27)
					(thickness 0.15)
				)
				(justify left bottom)
				(hide yes)
			)
		)
		(property "MPN" "CR0402-FX-1022GLF"
			(at 86.36 138.43 0)
			(effects
				(font
					(size 1.27 1.27)
					(thickness 0.15)
				)
				(justify left bottom)
				(hide yes)
			)
		)
		(property "Val" "10k2"
			(at 60.96 118.11 0)
			(effects
				(font
					(size 1.27 1.27)
					(thickness 0.15)
				)
				(justify left bottom)
			)
		)
		(property "License" "Apache-2.0"
			(at 86.36 143.51 0)
			(effects
				(font
					(size 1.27 1.27)
					(thickness 0.15)
				)
				(justify left bottom)
				(hide yes)
			)
		)
		(property "Author" "Antmicro"
			(at 86.36 146.05 0)
			(effects
				(font
					(size 1.27 1.27)
					(thickness 0.15)
				)
				(justify left bottom)
				(hide yes)
			)
		)
		(property "Tolerance" "1%"
			(at 86.36 128.27 0)
			(effects
				(font
					(size 1.27 1.27)
				)
				(justify left bottom)
				(hide yes)
			)
		)
		(pin "1"
		)
		(pin "2"
		)
		(instances
			(project "artix-dc-scm"
				(path ""
					(reference "R149")
					(unit 1)
				)
			)
		)
	)
	(symbol
		(lib_id "antmicroResistors0402:R_10k2_0402")
		(at 66.04 115.57 0)
		(unit 1)
		(exclude_from_sim no)
		(in_bom yes)
		(on_board yes)
		(dnp no)
		(property "Reference" "R150"
			(at 76.2 114.3 0)
			(effects
				(font
					(size 1.27 1.27)
				)
				(justify right)
			)
		)
		(property "Value" "R_10k2_0402"
			(at 86.36 128.27 0)
			(effects
				(font
					(size 1.27 1.27)
					(thickness 0.15)
				)
				(justify left bottom)
				(hide yes)
			)
		)
		(property "Footprint" "antmicro-footprints:R_0402_1005Metric"
			(at 86.36 130.81 0)
			(effects
				(font
					(size 1.27 1.27)
					(thickness 0.15)
				)
				(justify left bottom)
				(hide yes)
			)
		)
		(property "Datasheet" "https://www.bourns.com/docs/product-datasheets/cr.pdf"
			(at 86.36 133.35 0)
			(effects
				(font
					(size 1.27 1.27)
					(thickness 0.15)
				)
				(justify left bottom)
				(hide yes)
			)
		)
		(property "Description" "SMD Chip Resistor"
			(at 66.04 115.57 0)
			(effects
				(font
					(size 1.27 1.27)
				)
				(hide yes)
			)
		)
		(property "Manufacturer" "Bourns"
			(at 86.36 138.43 0)
			(effects
				(font
					(size 1.27 1.27)
					(thickness 0.15)
				)
				(justify left bottom)
				(hide yes)
			)
		)
		(property "MPN" "CR0402-FX-1022GLF"
			(at 86.36 135.89 0)
			(effects
				(font
					(size 1.27 1.27)
					(thickness 0.15)
				)
				(justify left bottom)
				(hide yes)
			)
		)
		(property "Val" "10k2"
			(at 60.96 115.57 0)
			(effects
				(font
					(size 1.27 1.27)
					(thickness 0.15)
				)
				(justify left bottom)
			)
		)
		(property "License" "Apache-2.0"
			(at 86.36 140.97 0)
			(effects
				(font
					(size 1.27 1.27)
					(thickness 0.15)
				)
				(justify left bottom)
				(hide yes)
			)
		)
		(property "Author" "Antmicro"
			(at 86.36 143.51 0)
			(effects
				(font
					(size 1.27 1.27)
					(thickness 0.15)
				)
				(justify left bottom)
				(hide yes)
			)
		)
		(property "Tolerance" "1%"
			(at 86.36 125.73 0)
			(effects
				(font
					(size 1.27 1.27)
				)
				(justify left bottom)
				(hide yes)
			)
		)
		(pin "1"
		)
		(pin "2"
		)
		(instances
			(project "artix-dc-scm"
				(path ""
					(reference "R150")
					(unit 1)
				)
			)
		)
	)
	(symbol
		(lib_id "antmicroResistors0402:R_10k2_0402")
		(at 66.04 138.43 0)
		(unit 1)
		(exclude_from_sim no)
		(in_bom yes)
		(on_board yes)
		(dnp no)
		(property "Reference" "R153"
			(at 76.2 137.16 0)
			(effects
				(font
					(size 1.27 1.27)
				)
				(justify right)
			)
		)
		(property "Value" "R_10k2_0402"
			(at 86.36 151.13 0)
			(effects
				(font
					(size 1.27 1.27)
					(thickness 0.15)
				)
				(justify left bottom)
				(hide yes)
			)
		)
		(property "Footprint" "antmicro-footprints:R_0402_1005Metric"
			(at 86.36 153.67 0)
			(effects
				(font
					(size 1.27 1.27)
					(thickness 0.15)
				)
				(justify left bottom)
				(hide yes)
			)
		)
		(property "Datasheet" "https://www.bourns.com/docs/product-datasheets/cr.pdf"
			(at 86.36 156.21 0)
			(effects
				(font
					(size 1.27 1.27)
					(thickness 0.15)
				)
				(justify left bottom)
				(hide yes)
			)
		)
		(property "Description" "SMD Chip Resistor"
			(at 66.04 138.43 0)
			(effects
				(font
					(size 1.27 1.27)
				)
				(hide yes)
			)
		)
		(property "Manufacturer" "Bourns"
			(at 86.36 161.29 0)
			(effects
				(font
					(size 1.27 1.27)
					(thickness 0.15)
				)
				(justify left bottom)
				(hide yes)
			)
		)
		(property "MPN" "CR0402-FX-1022GLF"
			(at 86.36 158.75 0)
			(effects
				(font
					(size 1.27 1.27)
					(thickness 0.15)
				)
				(justify left bottom)
				(hide yes)
			)
		)
		(property "Val" "10k2"
			(at 60.96 138.43 0)
			(effects
				(font
					(size 1.27 1.27)
					(thickness 0.15)
				)
				(justify left bottom)
			)
		)
		(property "License" "Apache-2.0"
			(at 86.36 163.83 0)
			(effects
				(font
					(size 1.27 1.27)
					(thickness 0.15)
				)
				(justify left bottom)
				(hide yes)
			)
		)
		(property "Author" "Antmicro"
			(at 86.36 166.37 0)
			(effects
				(font
					(size 1.27 1.27)
					(thickness 0.15)
				)
				(justify left bottom)
				(hide yes)
			)
		)
		(property "Tolerance" "1%"
			(at 86.36 148.59 0)
			(effects
				(font
					(size 1.27 1.27)
				)
				(justify left bottom)
				(hide yes)
			)
		)
		(pin "1"
		)
		(pin "2"
		)
		(instances
			(project "artix-dc-scm"
				(path ""
					(reference "R153")
					(unit 1)
				)
			)
		)
	)
	(symbol
		(lib_id "antmicroResistors0402:R_10k2_0402")
		(at 66.04 132.08 0)
		(unit 1)
		(exclude_from_sim no)
		(in_bom yes)
		(on_board yes)
		(dnp no)
		(property "Reference" "R152"
			(at 76.2 130.81 0)
			(effects
				(font
					(size 1.27 1.27)
				)
				(justify right)
			)
		)
		(property "Value" "R_10k2_0402"
			(at 86.36 144.78 0)
			(effects
				(font
					(size 1.27 1.27)
					(thickness 0.15)
				)
				(justify left bottom)
				(hide yes)
			)
		)
		(property "Footprint" "antmicro-footprints:R_0402_1005Metric"
			(at 86.36 147.32 0)
			(effects
				(font
					(size 1.27 1.27)
					(thickness 0.15)
				)
				(justify left bottom)
				(hide yes)
			)
		)
		(property "Datasheet" "https://www.bourns.com/docs/product-datasheets/cr.pdf"
			(at 86.36 149.86 0)
			(effects
				(font
					(size 1.27 1.27)
					(thickness 0.15)
				)
				(justify left bottom)
				(hide yes)
			)
		)
		(property "Description" "SMD Chip Resistor"
			(at 66.04 132.08 0)
			(effects
				(font
					(size 1.27 1.27)
				)
				(hide yes)
			)
		)
		(property "Manufacturer" "Bourns"
			(at 86.36 154.94 0)
			(effects
				(font
					(size 1.27 1.27)
					(thickness 0.15)
				)
				(justify left bottom)
				(hide yes)
			)
		)
		(property "MPN" "CR0402-FX-1022GLF"
			(at 86.36 152.4 0)
			(effects
				(font
					(size 1.27 1.27)
					(thickness 0.15)
				)
				(justify left bottom)
				(hide yes)
			)
		)
		(property "Val" "10k2"
			(at 60.96 132.08 0)
			(effects
				(font
					(size 1.27 1.27)
					(thickness 0.15)
				)
				(justify left bottom)
			)
		)
		(property "License" "Apache-2.0"
			(at 86.36 157.48 0)
			(effects
				(font
					(size 1.27 1.27)
					(thickness 0.15)
				)
				(justify left bottom)
				(hide yes)
			)
		)
		(property "Author" "Antmicro"
			(at 86.36 160.02 0)
			(effects
				(font
					(size 1.27 1.27)
					(thickness 0.15)
				)
				(justify left bottom)
				(hide yes)
			)
		)
		(property "Tolerance" "1%"
			(at 86.36 142.24 0)
			(effects
				(font
					(size 1.27 1.27)
				)
				(justify left bottom)
				(hide yes)
			)
		)
		(pin "1"
		)
		(pin "2"
		)
		(instances
			(project "artix-dc-scm"
				(path ""
					(reference "R152")
					(unit 1)
				)
			)
		)
	)
	(symbol
		(lib_id "antmicroResistors0402:R_10k2_0402")
		(at 66.04 135.89 0)
		(unit 1)
		(exclude_from_sim no)
		(in_bom yes)
		(on_board yes)
		(dnp no)
		(property "Reference" "R151"
			(at 76.2 134.62 0)
			(effects
				(font
					(size 1.27 1.27)
				)
				(justify right)
			)
		)
		(property "Value" "R_10k2_0402"
			(at 86.36 148.59 0)
			(effects
				(font
					(size 1.27 1.27)
					(thickness 0.15)
				)
				(justify left bottom)
				(hide yes)
			)
		)
		(property "Footprint" "antmicro-footprints:R_0402_1005Metric"
			(at 86.36 151.13 0)
			(effects
				(font
					(size 1.27 1.27)
					(thickness 0.15)
				)
				(justify left bottom)
				(hide yes)
			)
		)
		(property "Datasheet" "https://www.bourns.com/docs/product-datasheets/cr.pdf"
			(at 86.36 153.67 0)
			(effects
				(font
					(size 1.27 1.27)
					(thickness 0.15)
				)
				(justify left bottom)
				(hide yes)
			)
		)
		(property "Description" "SMD Chip Resistor"
			(at 66.04 135.89 0)
			(effects
				(font
					(size 1.27 1.27)
				)
				(hide yes)
			)
		)
		(property "Manufacturer" "Bourns"
			(at 86.36 158.75 0)
			(effects
				(font
					(size 1.27 1.27)
					(thickness 0.15)
				)
				(justify left bottom)
				(hide yes)
			)
		)
		(property "MPN" "CR0402-FX-1022GLF"
			(at 86.36 156.21 0)
			(effects
				(font
					(size 1.27 1.27)
					(thickness 0.15)
				)
				(justify left bottom)
				(hide yes)
			)
		)
		(property "Val" "10k2"
			(at 60.96 135.89 0)
			(effects
				(font
					(size 1.27 1.27)
					(thickness 0.15)
				)
				(justify left bottom)
			)
		)
		(property "License" "Apache-2.0"
			(at 86.36 161.29 0)
			(effects
				(font
					(size 1.27 1.27)
					(thickness 0.15)
				)
				(justify left bottom)
				(hide yes)
			)
		)
		(property "Author" "Antmicro"
			(at 86.36 163.83 0)
			(effects
				(font
					(size 1.27 1.27)
					(thickness 0.15)
				)
				(justify left bottom)
				(hide yes)
			)
		)
		(property "Tolerance" "1%"
			(at 86.36 146.05 0)
			(effects
				(font
					(size 1.27 1.27)
				)
				(justify left bottom)
				(hide yes)
			)
		)
		(pin "1"
		)
		(pin "2"
		)
		(instances
			(project "artix-dc-scm"
				(path ""
					(reference "R151")
					(unit 1)
				)
			)
		)
	)
	(symbol
		(lib_id "antmicroResistors0402:R_10k2_0402")
		(at 140.97 134.62 90)
		(unit 1)
		(exclude_from_sim no)
		(in_bom yes)
		(on_board yes)
		(dnp no)
		(property "Reference" "R156"
			(at 142.24 130.81 90)
			(effects
				(font
					(size 1.27 1.27)
				)
				(justify right)
			)
		)
		(property "Value" "R_10k2_0402"
			(at 153.67 114.3 0)
			(effects
				(font
					(size 1.27 1.27)
					(thickness 0.15)
				)
				(justify left bottom)
				(hide yes)
			)
		)
		(property "Footprint" "antmicro-footprints:R_0402_1005Metric"
			(at 156.21 114.3 0)
			(effects
				(font
					(size 1.27 1.27)
					(thickness 0.15)
				)
				(justify left bottom)
				(hide yes)
			)
		)
		(property "Datasheet" "https://www.bourns.com/docs/product-datasheets/cr.pdf"
			(at 158.75 114.3 0)
			(effects
				(font
					(size 1.27 1.27)
					(thickness 0.15)
				)
				(justify left bottom)
				(hide yes)
			)
		)
		(property "Description" "SMD Chip Resistor"
			(at 140.97 134.62 0)
			(effects
				(font
					(size 1.27 1.27)
				)
				(hide yes)
			)
		)
		(property "Manufacturer" "Bourns"
			(at 163.83 114.3 0)
			(effects
				(font
					(size 1.27 1.27)
					(thickness 0.15)
				)
				(justify left bottom)
				(hide yes)
			)
		)
		(property "MPN" "CR0402-FX-1022GLF"
			(at 161.29 114.3 0)
			(effects
				(font
					(size 1.27 1.27)
					(thickness 0.15)
				)
				(justify left bottom)
				(hide yes)
			)
		)
		(property "Val" "10k2"
			(at 142.24 133.35 90)
			(effects
				(font
					(size 1.27 1.27)
					(thickness 0.15)
				)
				(justify right)
			)
		)
		(property "License" "Apache-2.0"
			(at 166.37 114.3 0)
			(effects
				(font
					(size 1.27 1.27)
					(thickness 0.15)
				)
				(justify left bottom)
				(hide yes)
			)
		)
		(property "Author" "Antmicro"
			(at 168.91 114.3 0)
			(effects
				(font
					(size 1.27 1.27)
					(thickness 0.15)
				)
				(justify left bottom)
				(hide yes)
			)
		)
		(property "Tolerance" "1%"
			(at 151.13 114.3 0)
			(effects
				(font
					(size 1.27 1.27)
				)
				(justify left bottom)
				(hide yes)
			)
		)
		(pin "1"
		)
		(pin "2"
		)
		(instances
			(project "artix-dc-scm"
				(path ""
					(reference "R156")
					(unit 1)
				)
			)
		)
	)
	(symbol
		(lib_id "antmicroResistors0402:R_10k2_0402")
		(at 66.04 129.54 0)
		(unit 1)
		(exclude_from_sim no)
		(in_bom yes)
		(on_board yes)
		(dnp no)
		(property "Reference" "R158"
			(at 76.2 128.27 0)
			(effects
				(font
					(size 1.27 1.27)
				)
				(justify right)
			)
		)
		(property "Value" "R_10k2_0402"
			(at 86.36 142.24 0)
			(effects
				(font
					(size 1.27 1.27)
					(thickness 0.15)
				)
				(justify left bottom)
				(hide yes)
			)
		)
		(property "Footprint" "antmicro-footprints:R_0402_1005Metric"
			(at 86.36 144.78 0)
			(effects
				(font
					(size 1.27 1.27)
					(thickness 0.15)
				)
				(justify left bottom)
				(hide yes)
			)
		)
		(property "Datasheet" "https://www.bourns.com/docs/product-datasheets/cr.pdf"
			(at 86.36 147.32 0)
			(effects
				(font
					(size 1.27 1.27)
					(thickness 0.15)
				)
				(justify left bottom)
				(hide yes)
			)
		)
		(property "Description" "SMD Chip Resistor"
			(at 66.04 129.54 0)
			(effects
				(font
					(size 1.27 1.27)
				)
				(hide yes)
			)
		)
		(property "Manufacturer" "Bourns"
			(at 86.36 152.4 0)
			(effects
				(font
					(size 1.27 1.27)
					(thickness 0.15)
				)
				(justify left bottom)
				(hide yes)
			)
		)
		(property "MPN" "CR0402-FX-1022GLF"
			(at 86.36 149.86 0)
			(effects
				(font
					(size 1.27 1.27)
					(thickness 0.15)
				)
				(justify left bottom)
				(hide yes)
			)
		)
		(property "Val" "10k2"
			(at 60.96 129.54 0)
			(effects
				(font
					(size 1.27 1.27)
					(thickness 0.15)
				)
				(justify left bottom)
			)
		)
		(property "License" "Apache-2.0"
			(at 86.36 154.94 0)
			(effects
				(font
					(size 1.27 1.27)
					(thickness 0.15)
				)
				(justify left bottom)
				(hide yes)
			)
		)
		(property "Author" "Antmicro"
			(at 86.36 157.48 0)
			(effects
				(font
					(size 1.27 1.27)
					(thickness 0.15)
				)
				(justify left bottom)
				(hide yes)
			)
		)
		(property "Tolerance" "1%"
			(at 86.36 139.7 0)
			(effects
				(font
					(size 1.27 1.27)
				)
				(justify left bottom)
				(hide yes)
			)
		)
		(pin "1"
		)
		(pin "2"
		)
		(instances
			(project "artix-dc-scm"
				(path ""
					(reference "R158")
					(unit 1)
				)
			)
		)
	)
	(symbol
		(lib_id "antmicroResistors0402:R_10k2_0402")
		(at 66.04 127 0)
		(unit 1)
		(exclude_from_sim no)
		(in_bom yes)
		(on_board yes)
		(dnp no)
		(property "Reference" "R157"
			(at 76.2 125.73 0)
			(effects
				(font
					(size 1.27 1.27)
				)
				(justify right)
			)
		)
		(property "Value" "R_10k2_0402"
			(at 86.36 139.7 0)
			(effects
				(font
					(size 1.27 1.27)
					(thickness 0.15)
				)
				(justify left bottom)
				(hide yes)
			)
		)
		(property "Footprint" "antmicro-footprints:R_0402_1005Metric"
			(at 86.36 142.24 0)
			(effects
				(font
					(size 1.27 1.27)
					(thickness 0.15)
				)
				(justify left bottom)
				(hide yes)
			)
		)
		(property "Datasheet" "https://www.bourns.com/docs/product-datasheets/cr.pdf"
			(at 86.36 144.78 0)
			(effects
				(font
					(size 1.27 1.27)
					(thickness 0.15)
				)
				(justify left bottom)
				(hide yes)
			)
		)
		(property "Description" "SMD Chip Resistor"
			(at 66.04 127 0)
			(effects
				(font
					(size 1.27 1.27)
				)
				(hide yes)
			)
		)
		(property "Manufacturer" "Bourns"
			(at 86.36 149.86 0)
			(effects
				(font
					(size 1.27 1.27)
					(thickness 0.15)
				)
				(justify left bottom)
				(hide yes)
			)
		)
		(property "MPN" "CR0402-FX-1022GLF"
			(at 86.36 147.32 0)
			(effects
				(font
					(size 1.27 1.27)
					(thickness 0.15)
				)
				(justify left bottom)
				(hide yes)
			)
		)
		(property "Val" "10k2"
			(at 60.96 127 0)
			(effects
				(font
					(size 1.27 1.27)
					(thickness 0.15)
				)
				(justify left bottom)
			)
		)
		(property "License" "Apache-2.0"
			(at 86.36 152.4 0)
			(effects
				(font
					(size 1.27 1.27)
					(thickness 0.15)
				)
				(justify left bottom)
				(hide yes)
			)
		)
		(property "Author" "Antmicro"
			(at 86.36 154.94 0)
			(effects
				(font
					(size 1.27 1.27)
					(thickness 0.15)
				)
				(justify left bottom)
				(hide yes)
			)
		)
		(property "Tolerance" "1%"
			(at 86.36 137.16 0)
			(effects
				(font
					(size 1.27 1.27)
				)
				(justify left bottom)
				(hide yes)
			)
		)
		(pin "1"
		)
		(pin "2"
		)
		(instances
			(project "artix-dc-scm"
				(path ""
					(reference "R157")
					(unit 1)
				)
			)
		)
	)
	(symbol
		(lib_id "antmicroCapacitors0402:C_4u7_0402")
		(at 290.83 92.71 270)
		(mirror x)
		(unit 1)
		(exclude_from_sim no)
		(in_bom yes)
		(on_board yes)
		(dnp no)
		(property "Reference" "C200"
			(at 291.465 88.265 90)
			(effects
				(font
					(size 1.27 1.27)
				)
				(justify left)
			)
		)
		(property "Value" "C_4u7_0402"
			(at 280.67 72.39 0)
			(effects
				(font
					(size 1.27 1.27)
					(thickness 0.15)
				)
				(justify left bottom)
				(hide yes)
			)
		)
		(property "Footprint" "antmicro-footprints:C_0402_1005Metric"
			(at 278.13 72.39 0)
			(effects
				(font
					(size 1.27 1.27)
					(thickness 0.15)
				)
				(justify left bottom)
				(hide yes)
			)
		)
		(property "Datasheet" "https://www.murata.com/products/productdetail?partno=GRM155R61A475MEAA%23"
			(at 275.59 72.39 0)
			(effects
				(font
					(size 1.27 1.27)
					(thickness 0.15)
				)
				(justify left bottom)
				(hide yes)
			)
		)
		(property "Description" "SMD Multilayer Ceramic Capacitor, 4.7 µF, 10 V, 0402 [1005 Metric], ± 20%, X5R, GRM Series"
			(at 290.83 92.71 0)
			(effects
				(font
					(size 1.27 1.27)
				)
				(hide yes)
			)
		)
		(property "Manufacturer" "Murata"
			(at 270.51 72.39 0)
			(effects
				(font
					(size 1.27 1.27)
					(thickness 0.15)
				)
				(justify left bottom)
				(hide yes)
			)
		)
		(property "MPN" "GRM155R61A475MEAAD"
			(at 273.05 72.39 0)
			(effects
				(font
					(size 1.27 1.27)
					(thickness 0.15)
				)
				(justify left bottom)
				(hide yes)
			)
		)
		(property "Val" "4u7"
			(at 291.465 92.075 90)
			(effects
				(font
					(size 1.27 1.27)
					(thickness 0.15)
				)
				(justify left)
			)
		)
		(property "License" "Apache-2.0"
			(at 267.97 72.39 0)
			(effects
				(font
					(size 1.27 1.27)
					(thickness 0.15)
				)
				(justify left bottom)
				(hide yes)
			)
		)
		(property "Author" "Antmicro"
			(at 265.43 72.39 0)
			(effects
				(font
					(size 1.27 1.27)
					(thickness 0.15)
				)
				(justify left bottom)
				(hide yes)
			)
		)
		(property "Voltage" ""
			(at 262.89 72.39 0)
			(effects
				(font
					(size 1.27 1.27)
				)
				(justify left bottom)
				(hide yes)
			)
		)
		(property "Dielectric" ""
			(at 260.35 72.39 0)
			(effects
				(font
					(size 1.27 1.27)
				)
				(justify left bottom)
				(hide yes)
			)
		)
		(pin "1"
		)
		(pin "2"
		)
		(instances
			(project "artix-dc-scm"
				(path ""
					(reference "C200")
					(unit 1)
				)
			)
		)
	)
	(symbol
		(lib_id "antmicroCapacitors0402:C_470n_0402")
		(at 283.21 92.71 270)
		(mirror x)
		(unit 1)
		(exclude_from_sim no)
		(in_bom yes)
		(on_board yes)
		(dnp no)
		(property "Reference" "C204"
			(at 283.845 88.265 90)
			(effects
				(font
					(size 1.27 1.27)
				)
				(justify left)
			)
		)
		(property "Value" "C_470n_0402"
			(at 273.05 72.39 0)
			(effects
				(font
					(size 1.27 1.27)
					(thickness 0.15)
				)
				(justify left bottom)
				(hide yes)
			)
		)
		(property "Footprint" "antmicro-footprints:C_0402_1005Metric"
			(at 270.51 72.39 0)
			(effects
				(font
					(size 1.27 1.27)
					(thickness 0.15)
				)
				(justify left bottom)
				(hide yes)
			)
		)
		(property "Datasheet" "https://product.tdk.com/en/search/capacitor/ceramic/mlcc/info?part_no=C1005X5R1E474M050BB"
			(at 267.97 72.39 0)
			(effects
				(font
					(size 1.27 1.27)
					(thickness 0.15)
				)
				(justify left bottom)
				(hide yes)
			)
		)
		(property "Description" "SMD Multilayer Ceramic Capacitor, 0.47 µF, 25 V, 0402 [1005 Metric], ± 20%, X5R, C"
			(at 283.21 92.71 0)
			(effects
				(font
					(size 1.27 1.27)
				)
				(hide yes)
			)
		)
		(property "Manufacturer" "TDK"
			(at 262.89 72.39 0)
			(effects
				(font
					(size 1.27 1.27)
					(thickness 0.15)
				)
				(justify left bottom)
				(hide yes)
			)
		)
		(property "MPN" "C1005X5R1E474M050BB"
			(at 265.43 72.39 0)
			(effects
				(font
					(size 1.27 1.27)
					(thickness 0.15)
				)
				(justify left bottom)
				(hide yes)
			)
		)
		(property "Val" "470n"
			(at 283.845 92.075 90)
			(effects
				(font
					(size 1.27 1.27)
					(thickness 0.15)
				)
				(justify left)
			)
		)
		(property "License" "Apache-2.0"
			(at 260.35 72.39 0)
			(effects
				(font
					(size 1.27 1.27)
					(thickness 0.15)
				)
				(justify left bottom)
				(hide yes)
			)
		)
		(property "Author" "Antmicro"
			(at 257.81 72.39 0)
			(effects
				(font
					(size 1.27 1.27)
					(thickness 0.15)
				)
				(justify left bottom)
				(hide yes)
			)
		)
		(property "Voltage" ""
			(at 255.27 72.39 0)
			(effects
				(font
					(size 1.27 1.27)
				)
				(justify left bottom)
				(hide yes)
			)
		)
		(property "Dielectric" ""
			(at 252.73 72.39 0)
			(effects
				(font
					(size 1.27 1.27)
				)
				(justify left bottom)
				(hide yes)
			)
		)
		(pin "1"
		)
		(pin "2"
		)
		(instances
			(project "artix-dc-scm"
				(path ""
					(reference "C204")
					(unit 1)
				)
			)
		)
	)
	(symbol
		(lib_id "antmicroCapacitors0402:C_10n_0402")
		(at 266.7 92.71 270)
		(mirror x)
		(unit 1)
		(exclude_from_sim no)
		(in_bom yes)
		(on_board yes)
		(dnp no)
		(property "Reference" "C209"
			(at 267.335 88.265 90)
			(effects
				(font
					(size 1.27 1.27)
				)
				(justify left)
			)
		)
		(property "Value" "C_10n_0402"
			(at 256.54 72.39 0)
			(effects
				(font
					(size 1.27 1.27)
					(thickness 0.15)
				)
				(justify left bottom)
				(hide yes)
			)
		)
		(property "Footprint" "antmicro-footprints:C_0402_1005Metric"
			(at 254 72.39 0)
			(effects
				(font
					(size 1.27 1.27)
					(thickness 0.15)
				)
				(justify left bottom)
				(hide yes)
			)
		)
		(property "Datasheet" "https://www.murata.com/products/productdetail?partno=GRM155R71H103KA88%23"
			(at 251.46 72.39 0)
			(effects
				(font
					(size 1.27 1.27)
					(thickness 0.15)
				)
				(justify left bottom)
				(hide yes)
			)
		)
		(property "Description" "SMD Multilayer Ceramic Capacitor, 10000 pF, 50 V, 0402 [1005 Metric], ± 10%, X7R, GRM Series"
			(at 266.7 92.71 0)
			(effects
				(font
					(size 1.27 1.27)
				)
				(hide yes)
			)
		)
		(property "Manufacturer" "Murata"
			(at 246.38 72.39 0)
			(effects
				(font
					(size 1.27 1.27)
					(thickness 0.15)
				)
				(justify left bottom)
				(hide yes)
			)
		)
		(property "MPN" "GRM155R71H103KA88D"
			(at 248.92 72.39 0)
			(effects
				(font
					(size 1.27 1.27)
					(thickness 0.15)
				)
				(justify left bottom)
				(hide yes)
			)
		)
		(property "Val" "10n"
			(at 267.335 92.075 90)
			(effects
				(font
					(size 1.27 1.27)
					(thickness 0.15)
				)
				(justify left)
			)
		)
		(property "License" "Apache-2.0"
			(at 243.84 72.39 0)
			(effects
				(font
					(size 1.27 1.27)
					(thickness 0.15)
				)
				(justify left bottom)
				(hide yes)
			)
		)
		(property "Author" "Antmicro"
			(at 241.3 72.39 0)
			(effects
				(font
					(size 1.27 1.27)
					(thickness 0.15)
				)
				(justify left bottom)
				(hide yes)
			)
		)
		(property "Voltage" "50V"
			(at 238.76 72.39 0)
			(effects
				(font
					(size 1.27 1.27)
				)
				(justify left bottom)
				(hide yes)
			)
		)
		(property "Dielectric" "X7R"
			(at 236.22 72.39 0)
			(effects
				(font
					(size 1.27 1.27)
				)
				(justify left bottom)
				(hide yes)
			)
		)
		(pin "1"
		)
		(pin "2"
		)
		(instances
			(project "artix-dc-scm"
				(path ""
					(reference "C209")
					(unit 1)
				)
			)
		)
	)
	(symbol
		(lib_id "antmicroCapacitors0402:C_10n_0402")
		(at 274.32 92.71 270)
		(mirror x)
		(unit 1)
		(exclude_from_sim no)
		(in_bom yes)
		(on_board yes)
		(dnp no)
		(property "Reference" "C213"
			(at 274.955 88.265 90)
			(effects
				(font
					(size 1.27 1.27)
				)
				(justify left)
			)
		)
		(property "Value" "C_10n_0402"
			(at 264.16 72.39 0)
			(effects
				(font
					(size 1.27 1.27)
					(thickness 0.15)
				)
				(justify left bottom)
				(hide yes)
			)
		)
		(property "Footprint" "antmicro-footprints:C_0402_1005Metric"
			(at 261.62 72.39 0)
			(effects
				(font
					(size 1.27 1.27)
					(thickness 0.15)
				)
				(justify left bottom)
				(hide yes)
			)
		)
		(property "Datasheet" "https://www.murata.com/products/productdetail?partno=GRM155R71H103KA88%23"
			(at 259.08 72.39 0)
			(effects
				(font
					(size 1.27 1.27)
					(thickness 0.15)
				)
				(justify left bottom)
				(hide yes)
			)
		)
		(property "Description" "SMD Multilayer Ceramic Capacitor, 10000 pF, 50 V, 0402 [1005 Metric], ± 10%, X7R, GRM Series"
			(at 274.32 92.71 0)
			(effects
				(font
					(size 1.27 1.27)
				)
				(hide yes)
			)
		)
		(property "Manufacturer" "Murata"
			(at 254 72.39 0)
			(effects
				(font
					(size 1.27 1.27)
					(thickness 0.15)
				)
				(justify left bottom)
				(hide yes)
			)
		)
		(property "MPN" "GRM155R71H103KA88D"
			(at 256.54 72.39 0)
			(effects
				(font
					(size 1.27 1.27)
					(thickness 0.15)
				)
				(justify left bottom)
				(hide yes)
			)
		)
		(property "Val" "10n"
			(at 274.955 92.075 90)
			(effects
				(font
					(size 1.27 1.27)
					(thickness 0.15)
				)
				(justify left)
			)
		)
		(property "License" "Apache-2.0"
			(at 251.46 72.39 0)
			(effects
				(font
					(size 1.27 1.27)
					(thickness 0.15)
				)
				(justify left bottom)
				(hide yes)
			)
		)
		(property "Author" "Antmicro"
			(at 248.92 72.39 0)
			(effects
				(font
					(size 1.27 1.27)
					(thickness 0.15)
				)
				(justify left bottom)
				(hide yes)
			)
		)
		(property "Voltage" "50V"
			(at 246.38 72.39 0)
			(effects
				(font
					(size 1.27 1.27)
				)
				(justify left bottom)
				(hide yes)
			)
		)
		(property "Dielectric" "X7R"
			(at 243.84 72.39 0)
			(effects
				(font
					(size 1.27 1.27)
				)
				(justify left bottom)
				(hide yes)
			)
		)
		(pin "1"
		)
		(pin "2"
		)
		(instances
			(project "artix-dc-scm"
				(path ""
					(reference "C213")
					(unit 1)
				)
			)
		)
	)
	(symbol
		(lib_id "antmicroCapacitors0402:C_10n_0402")
		(at 274.32 113.03 270)
		(mirror x)
		(unit 1)
		(exclude_from_sim no)
		(in_bom yes)
		(on_board yes)
		(dnp no)
		(property "Reference" "C208"
			(at 274.955 108.585 90)
			(effects
				(font
					(size 1.27 1.27)
				)
				(justify left)
			)
		)
		(property "Value" "C_10n_0402"
			(at 264.16 92.71 0)
			(effects
				(font
					(size 1.27 1.27)
					(thickness 0.15)
				)
				(justify left bottom)
				(hide yes)
			)
		)
		(property "Footprint" "antmicro-footprints:C_0402_1005Metric"
			(at 261.62 92.71 0)
			(effects
				(font
					(size 1.27 1.27)
					(thickness 0.15)
				)
				(justify left bottom)
				(hide yes)
			)
		)
		(property "Datasheet" "https://www.murata.com/products/productdetail?partno=GRM155R71H103KA88%23"
			(at 259.08 92.71 0)
			(effects
				(font
					(size 1.27 1.27)
					(thickness 0.15)
				)
				(justify left bottom)
				(hide yes)
			)
		)
		(property "Description" "SMD Multilayer Ceramic Capacitor, 10000 pF, 50 V, 0402 [1005 Metric], ± 10%, X7R, GRM Series"
			(at 274.32 113.03 0)
			(effects
				(font
					(size 1.27 1.27)
				)
				(hide yes)
			)
		)
		(property "Manufacturer" "Murata"
			(at 254 92.71 0)
			(effects
				(font
					(size 1.27 1.27)
					(thickness 0.15)
				)
				(justify left bottom)
				(hide yes)
			)
		)
		(property "MPN" "GRM155R71H103KA88D"
			(at 256.54 92.71 0)
			(effects
				(font
					(size 1.27 1.27)
					(thickness 0.15)
				)
				(justify left bottom)
				(hide yes)
			)
		)
		(property "Val" "10n"
			(at 274.955 112.395 90)
			(effects
				(font
					(size 1.27 1.27)
					(thickness 0.15)
				)
				(justify left)
			)
		)
		(property "License" "Apache-2.0"
			(at 251.46 92.71 0)
			(effects
				(font
					(size 1.27 1.27)
					(thickness 0.15)
				)
				(justify left bottom)
				(hide yes)
			)
		)
		(property "Author" "Antmicro"
			(at 248.92 92.71 0)
			(effects
				(font
					(size 1.27 1.27)
					(thickness 0.15)
				)
				(justify left bottom)
				(hide yes)
			)
		)
		(property "Voltage" "50V"
			(at 246.38 92.71 0)
			(effects
				(font
					(size 1.27 1.27)
				)
				(justify left bottom)
				(hide yes)
			)
		)
		(property "Dielectric" "X7R"
			(at 243.84 92.71 0)
			(effects
				(font
					(size 1.27 1.27)
				)
				(justify left bottom)
				(hide yes)
			)
		)
		(pin "1"
		)
		(pin "2"
		)
		(instances
			(project "artix-dc-scm"
				(path ""
					(reference "C208")
					(unit 1)
				)
			)
		)
	)
	(symbol
		(lib_id "antmicroCapacitors0402:C_4u7_0402")
		(at 290.83 113.03 270)
		(mirror x)
		(unit 1)
		(exclude_from_sim no)
		(in_bom yes)
		(on_board yes)
		(dnp no)
		(property "Reference" "C199"
			(at 291.465 108.585 90)
			(effects
				(font
					(size 1.27 1.27)
				)
				(justify left)
			)
		)
		(property "Value" "C_4u7_0402"
			(at 280.67 92.71 0)
			(effects
				(font
					(size 1.27 1.27)
					(thickness 0.15)
				)
				(justify left bottom)
				(hide yes)
			)
		)
		(property "Footprint" "antmicro-footprints:C_0402_1005Metric"
			(at 278.13 92.71 0)
			(effects
				(font
					(size 1.27 1.27)
					(thickness 0.15)
				)
				(justify left bottom)
				(hide yes)
			)
		)
		(property "Datasheet" "https://www.murata.com/products/productdetail?partno=GRM155R61A475MEAA%23"
			(at 275.59 92.71 0)
			(effects
				(font
					(size 1.27 1.27)
					(thickness 0.15)
				)
				(justify left bottom)
				(hide yes)
			)
		)
		(property "Description" "SMD Multilayer Ceramic Capacitor, 4.7 µF, 10 V, 0402 [1005 Metric], ± 20%, X5R, GRM Series"
			(at 290.83 113.03 0)
			(effects
				(font
					(size 1.27 1.27)
				)
				(hide yes)
			)
		)
		(property "Manufacturer" "Murata"
			(at 270.51 92.71 0)
			(effects
				(font
					(size 1.27 1.27)
					(thickness 0.15)
				)
				(justify left bottom)
				(hide yes)
			)
		)
		(property "MPN" "GRM155R61A475MEAAD"
			(at 273.05 92.71 0)
			(effects
				(font
					(size 1.27 1.27)
					(thickness 0.15)
				)
				(justify left bottom)
				(hide yes)
			)
		)
		(property "Val" "4u7"
			(at 291.465 112.395 90)
			(effects
				(font
					(size 1.27 1.27)
					(thickness 0.15)
				)
				(justify left)
			)
		)
		(property "License" "Apache-2.0"
			(at 267.97 92.71 0)
			(effects
				(font
					(size 1.27 1.27)
					(thickness 0.15)
				)
				(justify left bottom)
				(hide yes)
			)
		)
		(property "Author" "Antmicro"
			(at 265.43 92.71 0)
			(effects
				(font
					(size 1.27 1.27)
					(thickness 0.15)
				)
				(justify left bottom)
				(hide yes)
			)
		)
		(property "Voltage" ""
			(at 262.89 92.71 0)
			(effects
				(font
					(size 1.27 1.27)
				)
				(justify left bottom)
				(hide yes)
			)
		)
		(property "Dielectric" ""
			(at 260.35 92.71 0)
			(effects
				(font
					(size 1.27 1.27)
				)
				(justify left bottom)
				(hide yes)
			)
		)
		(pin "1"
		)
		(pin "2"
		)
		(instances
			(project "artix-dc-scm"
				(path ""
					(reference "C199")
					(unit 1)
				)
			)
		)
	)
	(symbol
		(lib_id "antmicroCapacitors0402:C_100n_0402")
		(at 283.21 113.03 270)
		(mirror x)
		(unit 1)
		(exclude_from_sim no)
		(in_bom yes)
		(on_board yes)
		(dnp no)
		(property "Reference" "C203"
			(at 283.845 108.585 90)
			(effects
				(font
					(size 1.27 1.27)
				)
				(justify left)
			)
		)
		(property "Value" "C_100n_0402"
			(at 273.05 92.71 0)
			(effects
				(font
					(size 1.27 1.27)
					(thickness 0.15)
				)
				(justify left bottom)
				(hide yes)
			)
		)
		(property "Footprint" "antmicro-footprints:C_0402_1005Metric"
			(at 270.51 92.71 0)
			(effects
				(font
					(size 1.27 1.27)
					(thickness 0.15)
				)
				(justify left bottom)
				(hide yes)
			)
		)
		(property "Datasheet" "https://www.murata.com/products/productdetail?partno=GRM155R61H104KE14%23"
			(at 267.97 92.71 0)
			(effects
				(font
					(size 1.27 1.27)
					(thickness 0.15)
				)
				(justify left bottom)
				(hide yes)
			)
		)
		(property "Description" "SMD Multilayer Ceramic Capacitor, 0.1 µF, 50 V, 0402 [1005 Metric], ± 10%, X5R, GRM Series"
			(at 283.21 113.03 0)
			(effects
				(font
					(size 1.27 1.27)
				)
				(hide yes)
			)
		)
		(property "Manufacturer" "Murata"
			(at 262.89 92.71 0)
			(effects
				(font
					(size 1.27 1.27)
					(thickness 0.15)
				)
				(justify left bottom)
				(hide yes)
			)
		)
		(property "MPN" "GRM155R61H104KE14D"
			(at 265.43 92.71 0)
			(effects
				(font
					(size 1.27 1.27)
					(thickness 0.15)
				)
				(justify left bottom)
				(hide yes)
			)
		)
		(property "Val" "100n"
			(at 283.845 112.395 90)
			(effects
				(font
					(size 1.27 1.27)
					(thickness 0.15)
				)
				(justify left)
			)
		)
		(property "License" "Apache-2.0"
			(at 260.35 92.71 0)
			(effects
				(font
					(size 1.27 1.27)
					(thickness 0.15)
				)
				(justify left bottom)
				(hide yes)
			)
		)
		(property "Author" "Antmicro"
			(at 257.81 92.71 0)
			(effects
				(font
					(size 1.27 1.27)
					(thickness 0.15)
				)
				(justify left bottom)
				(hide yes)
			)
		)
		(property "Voltage" "50V"
			(at 255.27 92.71 0)
			(effects
				(font
					(size 1.27 1.27)
				)
				(justify left bottom)
				(hide yes)
			)
		)
		(property "Dielectric" "X5R"
			(at 252.73 92.71 0)
			(effects
				(font
					(size 1.27 1.27)
				)
				(justify left bottom)
				(hide yes)
			)
		)
		(pin "1"
		)
		(pin "2"
		)
		(instances
			(project "artix-dc-scm"
				(path ""
					(reference "C203")
					(unit 1)
				)
			)
		)
	)
	(symbol
		(lib_id "antmicropower:GND")
		(at 242.57 177.8 0)
		(unit 1)
		(exclude_from_sim no)
		(in_bom yes)
		(on_board yes)
		(dnp no)
		(property "Reference" "#PWR098"
			(at 242.57 184.15 0)
			(effects
				(font
					(size 1.27 1.27)
				)
				(hide yes)
			)
		)
		(property "Value" "GND"
			(at 242.57 181.61 0)
			(effects
				(font
					(size 1.27 1.27)
				)
			)
		)
		(property "Footprint" ""
			(at 242.57 177.8 0)
			(effects
				(font
					(size 1.27 1.27)
				)
				(hide yes)
			)
		)
		(property "Datasheet" ""
			(at 242.57 177.8 0)
			(effects
				(font
					(size 1.27 1.27)
				)
				(hide yes)
			)
		)
		(property "Description" ""
			(at 242.57 177.8 0)
			(effects
				(font
					(size 1.27 1.27)
				)
				(hide yes)
			)
		)
		(property "Author" "Antmicro"
			(at 251.46 185.42 0)
			(effects
				(font
					(size 1.27 1.27)
					(thickness 0.15)
				)
				(justify left bottom)
				(hide yes)
			)
		)
		(property "License" "Apache-2.0"
			(at 251.46 187.96 0)
			(effects
				(font
					(size 1.27 1.27)
					(thickness 0.15)
				)
				(justify left bottom)
				(hide yes)
			)
		)
		(pin "1"
		)
		(instances
			(project "artix-dc-scm"
				(path ""
					(reference "#PWR098")
					(unit 1)
				)
			)
		)
	)
	(symbol
		(lib_id "antmicroCapacitors0402:C_10n_0402")
		(at 266.7 73.66 90)
		(unit 1)
		(exclude_from_sim no)
		(in_bom yes)
		(on_board yes)
		(dnp no)
		(property "Reference" "C218"
			(at 267.335 69.215 90)
			(effects
				(font
					(size 1.27 1.27)
				)
				(justify right)
			)
		)
		(property "Value" "C_10n_0402"
			(at 276.86 53.34 0)
			(effects
				(font
					(size 1.27 1.27)
					(thickness 0.15)
				)
				(justify left bottom)
				(hide yes)
			)
		)
		(property "Footprint" "antmicro-footprints:C_0402_1005Metric"
			(at 279.4 53.34 0)
			(effects
				(font
					(size 1.27 1.27)
					(thickness 0.15)
				)
				(justify left bottom)
				(hide yes)
			)
		)
		(property "Datasheet" "https://www.murata.com/products/productdetail?partno=GRM155R71H103KA88%23"
			(at 281.94 53.34 0)
			(effects
				(font
					(size 1.27 1.27)
					(thickness 0.15)
				)
				(justify left bottom)
				(hide yes)
			)
		)
		(property "Description" "SMD Multilayer Ceramic Capacitor, 10000 pF, 50 V, 0402 [1005 Metric], ± 10%, X7R, GRM Series"
			(at 266.7 73.66 0)
			(effects
				(font
					(size 1.27 1.27)
				)
				(hide yes)
			)
		)
		(property "Manufacturer" "Murata"
			(at 287.02 53.34 0)
			(effects
				(font
					(size 1.27 1.27)
					(thickness 0.15)
				)
				(justify left bottom)
				(hide yes)
			)
		)
		(property "MPN" "GRM155R71H103KA88D"
			(at 284.48 53.34 0)
			(effects
				(font
					(size 1.27 1.27)
					(thickness 0.15)
				)
				(justify left bottom)
				(hide yes)
			)
		)
		(property "Val" "10n"
			(at 267.335 73.025 90)
			(effects
				(font
					(size 1.27 1.27)
					(thickness 0.15)
				)
				(justify right)
			)
		)
		(property "License" "Apache-2.0"
			(at 289.56 53.34 0)
			(effects
				(font
					(size 1.27 1.27)
					(thickness 0.15)
				)
				(justify left bottom)
				(hide yes)
			)
		)
		(property "Author" "Antmicro"
			(at 292.1 53.34 0)
			(effects
				(font
					(size 1.27 1.27)
					(thickness 0.15)
				)
				(justify left bottom)
				(hide yes)
			)
		)
		(property "Voltage" "50V"
			(at 294.64 53.34 0)
			(effects
				(font
					(size 1.27 1.27)
				)
				(justify left bottom)
				(hide yes)
			)
		)
		(property "Dielectric" "X7R"
			(at 297.18 53.34 0)
			(effects
				(font
					(size 1.27 1.27)
				)
				(justify left bottom)
				(hide yes)
			)
		)
		(pin "1"
		)
		(pin "2"
		)
		(instances
			(project "artix-dc-scm"
				(path ""
					(reference "C218")
					(unit 1)
				)
			)
		)
	)
	(symbol
		(lib_id "antmicroCapacitors0402:C_10n_0402")
		(at 257.81 73.66 90)
		(unit 1)
		(exclude_from_sim no)
		(in_bom yes)
		(on_board yes)
		(dnp no)
		(property "Reference" "C219"
			(at 258.445 69.215 90)
			(effects
				(font
					(size 1.27 1.27)
				)
				(justify right)
			)
		)
		(property "Value" "C_10n_0402"
			(at 267.97 53.34 0)
			(effects
				(font
					(size 1.27 1.27)
					(thickness 0.15)
				)
				(justify left bottom)
				(hide yes)
			)
		)
		(property "Footprint" "antmicro-footprints:C_0402_1005Metric"
			(at 270.51 53.34 0)
			(effects
				(font
					(size 1.27 1.27)
					(thickness 0.15)
				)
				(justify left bottom)
				(hide yes)
			)
		)
		(property "Datasheet" "https://www.murata.com/products/productdetail?partno=GRM155R71H103KA88%23"
			(at 273.05 53.34 0)
			(effects
				(font
					(size 1.27 1.27)
					(thickness 0.15)
				)
				(justify left bottom)
				(hide yes)
			)
		)
		(property "Description" "SMD Multilayer Ceramic Capacitor, 10000 pF, 50 V, 0402 [1005 Metric], ± 10%, X7R, GRM Series"
			(at 257.81 73.66 0)
			(effects
				(font
					(size 1.27 1.27)
				)
				(hide yes)
			)
		)
		(property "Manufacturer" "Murata"
			(at 278.13 53.34 0)
			(effects
				(font
					(size 1.27 1.27)
					(thickness 0.15)
				)
				(justify left bottom)
				(hide yes)
			)
		)
		(property "MPN" "GRM155R71H103KA88D"
			(at 275.59 53.34 0)
			(effects
				(font
					(size 1.27 1.27)
					(thickness 0.15)
				)
				(justify left bottom)
				(hide yes)
			)
		)
		(property "Val" "10n"
			(at 258.445 73.025 90)
			(effects
				(font
					(size 1.27 1.27)
					(thickness 0.15)
				)
				(justify right)
			)
		)
		(property "License" "Apache-2.0"
			(at 280.67 53.34 0)
			(effects
				(font
					(size 1.27 1.27)
					(thickness 0.15)
				)
				(justify left bottom)
				(hide yes)
			)
		)
		(property "Author" "Antmicro"
			(at 283.21 53.34 0)
			(effects
				(font
					(size 1.27 1.27)
					(thickness 0.15)
				)
				(justify left bottom)
				(hide yes)
			)
		)
		(property "Voltage" "50V"
			(at 285.75 53.34 0)
			(effects
				(font
					(size 1.27 1.27)
				)
				(justify left bottom)
				(hide yes)
			)
		)
		(property "Dielectric" "X7R"
			(at 288.29 53.34 0)
			(effects
				(font
					(size 1.27 1.27)
				)
				(justify left bottom)
				(hide yes)
			)
		)
		(pin "1"
		)
		(pin "2"
		)
		(instances
			(project "artix-dc-scm"
				(path ""
					(reference "C219")
					(unit 1)
				)
			)
		)
	)
	(symbol
		(lib_id "antmicroCapacitors0402:C_10n_0402")
		(at 283.21 73.66 90)
		(unit 1)
		(exclude_from_sim no)
		(in_bom yes)
		(on_board yes)
		(dnp no)
		(property "Reference" "C214"
			(at 283.845 69.215 90)
			(effects
				(font
					(size 1.27 1.27)
				)
				(justify right)
			)
		)
		(property "Value" "C_10n_0402"
			(at 293.37 53.34 0)
			(effects
				(font
					(size 1.27 1.27)
					(thickness 0.15)
				)
				(justify left bottom)
				(hide yes)
			)
		)
		(property "Footprint" "antmicro-footprints:C_0402_1005Metric"
			(at 295.91 53.34 0)
			(effects
				(font
					(size 1.27 1.27)
					(thickness 0.15)
				)
				(justify left bottom)
				(hide yes)
			)
		)
		(property "Datasheet" "https://www.murata.com/products/productdetail?partno=GRM155R71H103KA88%23"
			(at 298.45 53.34 0)
			(effects
				(font
					(size 1.27 1.27)
					(thickness 0.15)
				)
				(justify left bottom)
				(hide yes)
			)
		)
		(property "Description" "SMD Multilayer Ceramic Capacitor, 10000 pF, 50 V, 0402 [1005 Metric], ± 10%, X7R, GRM Series"
			(at 283.21 73.66 0)
			(effects
				(font
					(size 1.27 1.27)
				)
				(hide yes)
			)
		)
		(property "Manufacturer" "Murata"
			(at 303.53 53.34 0)
			(effects
				(font
					(size 1.27 1.27)
					(thickness 0.15)
				)
				(justify left bottom)
				(hide yes)
			)
		)
		(property "MPN" "GRM155R71H103KA88D"
			(at 300.99 53.34 0)
			(effects
				(font
					(size 1.27 1.27)
					(thickness 0.15)
				)
				(justify left bottom)
				(hide yes)
			)
		)
		(property "Val" "10n"
			(at 283.845 73.025 90)
			(effects
				(font
					(size 1.27 1.27)
					(thickness 0.15)
				)
				(justify right)
			)
		)
		(property "License" "Apache-2.0"
			(at 306.07 53.34 0)
			(effects
				(font
					(size 1.27 1.27)
					(thickness 0.15)
				)
				(justify left bottom)
				(hide yes)
			)
		)
		(property "Author" "Antmicro"
			(at 308.61 53.34 0)
			(effects
				(font
					(size 1.27 1.27)
					(thickness 0.15)
				)
				(justify left bottom)
				(hide yes)
			)
		)
		(property "Voltage" "50V"
			(at 311.15 53.34 0)
			(effects
				(font
					(size 1.27 1.27)
				)
				(justify left bottom)
				(hide yes)
			)
		)
		(property "Dielectric" "X7R"
			(at 313.69 53.34 0)
			(effects
				(font
					(size 1.27 1.27)
				)
				(justify left bottom)
				(hide yes)
			)
		)
		(pin "1"
		)
		(pin "2"
		)
		(instances
			(project "artix-dc-scm"
				(path ""
					(reference "C214")
					(unit 1)
				)
			)
		)
	)
	(symbol
		(lib_id "antmicroCapacitors0402:C_10n_0402")
		(at 274.32 73.66 90)
		(unit 1)
		(exclude_from_sim no)
		(in_bom yes)
		(on_board yes)
		(dnp no)
		(property "Reference" "C217"
			(at 274.955 69.215 90)
			(effects
				(font
					(size 1.27 1.27)
				)
				(justify right)
			)
		)
		(property "Value" "C_10n_0402"
			(at 284.48 53.34 0)
			(effects
				(font
					(size 1.27 1.27)
					(thickness 0.15)
				)
				(justify left bottom)
				(hide yes)
			)
		)
		(property "Footprint" "antmicro-footprints:C_0402_1005Metric"
			(at 287.02 53.34 0)
			(effects
				(font
					(size 1.27 1.27)
					(thickness 0.15)
				)
				(justify left bottom)
				(hide yes)
			)
		)
		(property "Datasheet" "https://www.murata.com/products/productdetail?partno=GRM155R71H103KA88%23"
			(at 289.56 53.34 0)
			(effects
				(font
					(size 1.27 1.27)
					(thickness 0.15)
				)
				(justify left bottom)
				(hide yes)
			)
		)
		(property "Description" "SMD Multilayer Ceramic Capacitor, 10000 pF, 50 V, 0402 [1005 Metric], ± 10%, X7R, GRM Series"
			(at 274.32 73.66 0)
			(effects
				(font
					(size 1.27 1.27)
				)
				(hide yes)
			)
		)
		(property "Manufacturer" "Murata"
			(at 294.64 53.34 0)
			(effects
				(font
					(size 1.27 1.27)
					(thickness 0.15)
				)
				(justify left bottom)
				(hide yes)
			)
		)
		(property "MPN" "GRM155R71H103KA88D"
			(at 292.1 53.34 0)
			(effects
				(font
					(size 1.27 1.27)
					(thickness 0.15)
				)
				(justify left bottom)
				(hide yes)
			)
		)
		(property "Val" "10n"
			(at 274.955 73.025 90)
			(effects
				(font
					(size 1.27 1.27)
					(thickness 0.15)
				)
				(justify right)
			)
		)
		(property "License" "Apache-2.0"
			(at 297.18 53.34 0)
			(effects
				(font
					(size 1.27 1.27)
					(thickness 0.15)
				)
				(justify left bottom)
				(hide yes)
			)
		)
		(property "Author" "Antmicro"
			(at 299.72 53.34 0)
			(effects
				(font
					(size 1.27 1.27)
					(thickness 0.15)
				)
				(justify left bottom)
				(hide yes)
			)
		)
		(property "Voltage" "50V"
			(at 302.26 53.34 0)
			(effects
				(font
					(size 1.27 1.27)
				)
				(justify left bottom)
				(hide yes)
			)
		)
		(property "Dielectric" "X7R"
			(at 304.8 53.34 0)
			(effects
				(font
					(size 1.27 1.27)
				)
				(justify left bottom)
				(hide yes)
			)
		)
		(pin "1"
		)
		(pin "2"
		)
		(instances
			(project "artix-dc-scm"
				(path ""
					(reference "C217")
					(unit 1)
				)
			)
		)
	)
	(symbol
		(lib_id "antmicroCapacitors0402:C_10n_0402")
		(at 160.02 113.03 90)
		(unit 1)
		(exclude_from_sim no)
		(in_bom yes)
		(on_board yes)
		(dnp no)
		(property "Reference" "C211"
			(at 160.655 108.585 90)
			(effects
				(font
					(size 1.27 1.27)
				)
				(justify right)
			)
		)
		(property "Value" "C_10n_0402"
			(at 170.18 92.71 0)
			(effects
				(font
					(size 1.27 1.27)
					(thickness 0.15)
				)
				(justify left bottom)
				(hide yes)
			)
		)
		(property "Footprint" "antmicro-footprints:C_0402_1005Metric"
			(at 172.72 92.71 0)
			(effects
				(font
					(size 1.27 1.27)
					(thickness 0.15)
				)
				(justify left bottom)
				(hide yes)
			)
		)
		(property "Datasheet" "https://www.murata.com/products/productdetail?partno=GRM155R71H103KA88%23"
			(at 175.26 92.71 0)
			(effects
				(font
					(size 1.27 1.27)
					(thickness 0.15)
				)
				(justify left bottom)
				(hide yes)
			)
		)
		(property "Description" "SMD Multilayer Ceramic Capacitor, 10000 pF, 50 V, 0402 [1005 Metric], ± 10%, X7R, GRM Series"
			(at 160.02 113.03 0)
			(effects
				(font
					(size 1.27 1.27)
				)
				(hide yes)
			)
		)
		(property "Manufacturer" "Murata"
			(at 180.34 92.71 0)
			(effects
				(font
					(size 1.27 1.27)
					(thickness 0.15)
				)
				(justify left bottom)
				(hide yes)
			)
		)
		(property "MPN" "GRM155R71H103KA88D"
			(at 177.8 92.71 0)
			(effects
				(font
					(size 1.27 1.27)
					(thickness 0.15)
				)
				(justify left bottom)
				(hide yes)
			)
		)
		(property "Val" "10n"
			(at 160.655 112.395 90)
			(effects
				(font
					(size 1.27 1.27)
					(thickness 0.15)
				)
				(justify right)
			)
		)
		(property "License" "Apache-2.0"
			(at 182.88 92.71 0)
			(effects
				(font
					(size 1.27 1.27)
					(thickness 0.15)
				)
				(justify left bottom)
				(hide yes)
			)
		)
		(property "Author" "Antmicro"
			(at 185.42 92.71 0)
			(effects
				(font
					(size 1.27 1.27)
					(thickness 0.15)
				)
				(justify left bottom)
				(hide yes)
			)
		)
		(property "Voltage" "50V"
			(at 187.96 92.71 0)
			(effects
				(font
					(size 1.27 1.27)
				)
				(justify left bottom)
				(hide yes)
			)
		)
		(property "Dielectric" "X7R"
			(at 190.5 92.71 0)
			(effects
				(font
					(size 1.27 1.27)
				)
				(justify left bottom)
				(hide yes)
			)
		)
		(pin "1"
		)
		(pin "2"
		)
		(instances
			(project "artix-dc-scm"
				(path ""
					(reference "C211")
					(unit 1)
				)
			)
		)
	)
	(symbol
		(lib_id "antmicroCapacitors0402:C_10n_0402")
		(at 290.83 73.66 90)
		(unit 1)
		(exclude_from_sim no)
		(in_bom yes)
		(on_board yes)
		(dnp no)
		(property "Reference" "C210"
			(at 291.465 69.215 90)
			(effects
				(font
					(size 1.27 1.27)
				)
				(justify right)
			)
		)
		(property "Value" "C_10n_0402"
			(at 300.99 53.34 0)
			(effects
				(font
					(size 1.27 1.27)
					(thickness 0.15)
				)
				(justify left bottom)
				(hide yes)
			)
		)
		(property "Footprint" "antmicro-footprints:C_0402_1005Metric"
			(at 303.53 53.34 0)
			(effects
				(font
					(size 1.27 1.27)
					(thickness 0.15)
				)
				(justify left bottom)
				(hide yes)
			)
		)
		(property "Datasheet" "https://www.murata.com/products/productdetail?partno=GRM155R71H103KA88%23"
			(at 306.07 53.34 0)
			(effects
				(font
					(size 1.27 1.27)
					(thickness 0.15)
				)
				(justify left bottom)
				(hide yes)
			)
		)
		(property "Description" "SMD Multilayer Ceramic Capacitor, 10000 pF, 50 V, 0402 [1005 Metric], ± 10%, X7R, GRM Series"
			(at 290.83 73.66 0)
			(effects
				(font
					(size 1.27 1.27)
				)
				(hide yes)
			)
		)
		(property "Manufacturer" "Murata"
			(at 311.15 53.34 0)
			(effects
				(font
					(size 1.27 1.27)
					(thickness 0.15)
				)
				(justify left bottom)
				(hide yes)
			)
		)
		(property "MPN" "GRM155R71H103KA88D"
			(at 308.61 53.34 0)
			(effects
				(font
					(size 1.27 1.27)
					(thickness 0.15)
				)
				(justify left bottom)
				(hide yes)
			)
		)
		(property "Val" "10n"
			(at 291.465 73.025 90)
			(effects
				(font
					(size 1.27 1.27)
					(thickness 0.15)
				)
				(justify right)
			)
		)
		(property "License" "Apache-2.0"
			(at 313.69 53.34 0)
			(effects
				(font
					(size 1.27 1.27)
					(thickness 0.15)
				)
				(justify left bottom)
				(hide yes)
			)
		)
		(property "Author" "Antmicro"
			(at 316.23 53.34 0)
			(effects
				(font
					(size 1.27 1.27)
					(thickness 0.15)
				)
				(justify left bottom)
				(hide yes)
			)
		)
		(property "Voltage" "50V"
			(at 318.77 53.34 0)
			(effects
				(font
					(size 1.27 1.27)
				)
				(justify left bottom)
				(hide yes)
			)
		)
		(property "Dielectric" "X7R"
			(at 321.31 53.34 0)
			(effects
				(font
					(size 1.27 1.27)
				)
				(justify left bottom)
				(hide yes)
			)
		)
		(pin "1"
		)
		(pin "2"
		)
		(instances
			(project "artix-dc-scm"
				(path ""
					(reference "C210")
					(unit 1)
				)
			)
		)
	)
	(symbol
		(lib_id "antmicroCapacitors0402:C_4u7_0402")
		(at 323.85 73.66 90)
		(unit 1)
		(exclude_from_sim no)
		(in_bom yes)
		(on_board yes)
		(dnp no)
		(property "Reference" "C196"
			(at 324.485 69.215 90)
			(effects
				(font
					(size 1.27 1.27)
				)
				(justify right)
			)
		)
		(property "Value" "C_4u7_0402"
			(at 334.01 53.34 0)
			(effects
				(font
					(size 1.27 1.27)
					(thickness 0.15)
				)
				(justify left bottom)
				(hide yes)
			)
		)
		(property "Footprint" "antmicro-footprints:C_0402_1005Metric"
			(at 336.55 53.34 0)
			(effects
				(font
					(size 1.27 1.27)
					(thickness 0.15)
				)
				(justify left bottom)
				(hide yes)
			)
		)
		(property "Datasheet" "https://www.murata.com/products/productdetail?partno=GRM155R61A475MEAA%23"
			(at 339.09 53.34 0)
			(effects
				(font
					(size 1.27 1.27)
					(thickness 0.15)
				)
				(justify left bottom)
				(hide yes)
			)
		)
		(property "Description" "SMD Multilayer Ceramic Capacitor, 4.7 µF, 10 V, 0402 [1005 Metric], ± 20%, X5R, GRM Series"
			(at 323.85 73.66 0)
			(effects
				(font
					(size 1.27 1.27)
				)
				(hide yes)
			)
		)
		(property "Manufacturer" "Murata"
			(at 344.17 53.34 0)
			(effects
				(font
					(size 1.27 1.27)
					(thickness 0.15)
				)
				(justify left bottom)
				(hide yes)
			)
		)
		(property "MPN" "GRM155R61A475MEAAD"
			(at 341.63 53.34 0)
			(effects
				(font
					(size 1.27 1.27)
					(thickness 0.15)
				)
				(justify left bottom)
				(hide yes)
			)
		)
		(property "Val" "4u7"
			(at 324.485 73.025 90)
			(effects
				(font
					(size 1.27 1.27)
					(thickness 0.15)
				)
				(justify right)
			)
		)
		(property "License" "Apache-2.0"
			(at 346.71 53.34 0)
			(effects
				(font
					(size 1.27 1.27)
					(thickness 0.15)
				)
				(justify left bottom)
				(hide yes)
			)
		)
		(property "Author" "Antmicro"
			(at 349.25 53.34 0)
			(effects
				(font
					(size 1.27 1.27)
					(thickness 0.15)
				)
				(justify left bottom)
				(hide yes)
			)
		)
		(property "Voltage" ""
			(at 351.79 53.34 0)
			(effects
				(font
					(size 1.27 1.27)
				)
				(justify left bottom)
				(hide yes)
			)
		)
		(property "Dielectric" ""
			(at 354.33 53.34 0)
			(effects
				(font
					(size 1.27 1.27)
				)
				(justify left bottom)
				(hide yes)
			)
		)
		(pin "1"
		)
		(pin "2"
		)
		(instances
			(project "artix-dc-scm"
				(path ""
					(reference "C196")
					(unit 1)
				)
			)
		)
	)
	(symbol
		(lib_id "antmicroCapacitors0402:C_470n_0402")
		(at 316.23 73.66 90)
		(unit 1)
		(exclude_from_sim no)
		(in_bom yes)
		(on_board yes)
		(dnp no)
		(property "Reference" "C197"
			(at 316.865 69.215 90)
			(effects
				(font
					(size 1.27 1.27)
				)
				(justify right)
			)
		)
		(property "Value" "C_470n_0402"
			(at 326.39 53.34 0)
			(effects
				(font
					(size 1.27 1.27)
					(thickness 0.15)
				)
				(justify left bottom)
				(hide yes)
			)
		)
		(property "Footprint" "antmicro-footprints:C_0402_1005Metric"
			(at 328.93 53.34 0)
			(effects
				(font
					(size 1.27 1.27)
					(thickness 0.15)
				)
				(justify left bottom)
				(hide yes)
			)
		)
		(property "Datasheet" "https://product.tdk.com/en/search/capacitor/ceramic/mlcc/info?part_no=C1005X5R1E474M050BB"
			(at 331.47 53.34 0)
			(effects
				(font
					(size 1.27 1.27)
					(thickness 0.15)
				)
				(justify left bottom)
				(hide yes)
			)
		)
		(property "Description" "SMD Multilayer Ceramic Capacitor, 0.47 µF, 25 V, 0402 [1005 Metric], ± 20%, X5R, C"
			(at 316.23 73.66 0)
			(effects
				(font
					(size 1.27 1.27)
				)
				(hide yes)
			)
		)
		(property "Manufacturer" "TDK"
			(at 336.55 53.34 0)
			(effects
				(font
					(size 1.27 1.27)
					(thickness 0.15)
				)
				(justify left bottom)
				(hide yes)
			)
		)
		(property "MPN" "C1005X5R1E474M050BB"
			(at 334.01 53.34 0)
			(effects
				(font
					(size 1.27 1.27)
					(thickness 0.15)
				)
				(justify left bottom)
				(hide yes)
			)
		)
		(property "Val" "470n"
			(at 316.865 73.025 90)
			(effects
				(font
					(size 1.27 1.27)
					(thickness 0.15)
				)
				(justify right)
			)
		)
		(property "License" "Apache-2.0"
			(at 339.09 53.34 0)
			(effects
				(font
					(size 1.27 1.27)
					(thickness 0.15)
				)
				(justify left bottom)
				(hide yes)
			)
		)
		(property "Author" "Antmicro"
			(at 341.63 53.34 0)
			(effects
				(font
					(size 1.27 1.27)
					(thickness 0.15)
				)
				(justify left bottom)
				(hide yes)
			)
		)
		(property "Voltage" ""
			(at 344.17 53.34 0)
			(effects
				(font
					(size 1.27 1.27)
				)
				(justify left bottom)
				(hide yes)
			)
		)
		(property "Dielectric" ""
			(at 346.71 53.34 0)
			(effects
				(font
					(size 1.27 1.27)
				)
				(justify left bottom)
				(hide yes)
			)
		)
		(pin "1"
		)
		(pin "2"
		)
		(instances
			(project "artix-dc-scm"
				(path ""
					(reference "C197")
					(unit 1)
				)
			)
		)
	)
	(symbol
		(lib_id "antmicroCapacitors0402:C_470n_0402")
		(at 307.34 73.66 90)
		(unit 1)
		(exclude_from_sim no)
		(in_bom yes)
		(on_board yes)
		(dnp no)
		(property "Reference" "C201"
			(at 307.975 69.215 90)
			(effects
				(font
					(size 1.27 1.27)
				)
				(justify right)
			)
		)
		(property "Value" "C_470n_0402"
			(at 317.5 53.34 0)
			(effects
				(font
					(size 1.27 1.27)
					(thickness 0.15)
				)
				(justify left bottom)
				(hide yes)
			)
		)
		(property "Footprint" "antmicro-footprints:C_0402_1005Metric"
			(at 320.04 53.34 0)
			(effects
				(font
					(size 1.27 1.27)
					(thickness 0.15)
				)
				(justify left bottom)
				(hide yes)
			)
		)
		(property "Datasheet" "https://product.tdk.com/en/search/capacitor/ceramic/mlcc/info?part_no=C1005X5R1E474M050BB"
			(at 322.58 53.34 0)
			(effects
				(font
					(size 1.27 1.27)
					(thickness 0.15)
				)
				(justify left bottom)
				(hide yes)
			)
		)
		(property "Description" "SMD Multilayer Ceramic Capacitor, 0.47 µF, 25 V, 0402 [1005 Metric], ± 20%, X5R, C"
			(at 307.34 73.66 0)
			(effects
				(font
					(size 1.27 1.27)
				)
				(hide yes)
			)
		)
		(property "Manufacturer" "TDK"
			(at 327.66 53.34 0)
			(effects
				(font
					(size 1.27 1.27)
					(thickness 0.15)
				)
				(justify left bottom)
				(hide yes)
			)
		)
		(property "MPN" "C1005X5R1E474M050BB"
			(at 325.12 53.34 0)
			(effects
				(font
					(size 1.27 1.27)
					(thickness 0.15)
				)
				(justify left bottom)
				(hide yes)
			)
		)
		(property "Val" "470n"
			(at 307.975 73.025 90)
			(effects
				(font
					(size 1.27 1.27)
					(thickness 0.15)
				)
				(justify right)
			)
		)
		(property "License" "Apache-2.0"
			(at 330.2 53.34 0)
			(effects
				(font
					(size 1.27 1.27)
					(thickness 0.15)
				)
				(justify left bottom)
				(hide yes)
			)
		)
		(property "Author" "Antmicro"
			(at 332.74 53.34 0)
			(effects
				(font
					(size 1.27 1.27)
					(thickness 0.15)
				)
				(justify left bottom)
				(hide yes)
			)
		)
		(property "Voltage" ""
			(at 335.28 53.34 0)
			(effects
				(font
					(size 1.27 1.27)
				)
				(justify left bottom)
				(hide yes)
			)
		)
		(property "Dielectric" ""
			(at 337.82 53.34 0)
			(effects
				(font
					(size 1.27 1.27)
				)
				(justify left bottom)
				(hide yes)
			)
		)
		(pin "1"
		)
		(pin "2"
		)
		(instances
			(project "artix-dc-scm"
				(path ""
					(reference "C201")
					(unit 1)
				)
			)
		)
	)
	(symbol
		(lib_id "antmicroCapacitors0402:C_470n_0402")
		(at 299.72 73.66 90)
		(unit 1)
		(exclude_from_sim no)
		(in_bom yes)
		(on_board yes)
		(dnp no)
		(property "Reference" "C205"
			(at 300.355 69.215 90)
			(effects
				(font
					(size 1.27 1.27)
				)
				(justify right)
			)
		)
		(property "Value" "C_470n_0402"
			(at 309.88 53.34 0)
			(effects
				(font
					(size 1.27 1.27)
					(thickness 0.15)
				)
				(justify left bottom)
				(hide yes)
			)
		)
		(property "Footprint" "antmicro-footprints:C_0402_1005Metric"
			(at 312.42 53.34 0)
			(effects
				(font
					(size 1.27 1.27)
					(thickness 0.15)
				)
				(justify left bottom)
				(hide yes)
			)
		)
		(property "Datasheet" "https://product.tdk.com/en/search/capacitor/ceramic/mlcc/info?part_no=C1005X5R1E474M050BB"
			(at 314.96 53.34 0)
			(effects
				(font
					(size 1.27 1.27)
					(thickness 0.15)
				)
				(justify left bottom)
				(hide yes)
			)
		)
		(property "Description" "SMD Multilayer Ceramic Capacitor, 0.47 µF, 25 V, 0402 [1005 Metric], ± 20%, X5R, C"
			(at 299.72 73.66 0)
			(effects
				(font
					(size 1.27 1.27)
				)
				(hide yes)
			)
		)
		(property "Manufacturer" "TDK"
			(at 320.04 53.34 0)
			(effects
				(font
					(size 1.27 1.27)
					(thickness 0.15)
				)
				(justify left bottom)
				(hide yes)
			)
		)
		(property "MPN" "C1005X5R1E474M050BB"
			(at 317.5 53.34 0)
			(effects
				(font
					(size 1.27 1.27)
					(thickness 0.15)
				)
				(justify left bottom)
				(hide yes)
			)
		)
		(property "Val" "470n"
			(at 300.355 73.025 90)
			(effects
				(font
					(size 1.27 1.27)
					(thickness 0.15)
				)
				(justify right)
			)
		)
		(property "License" "Apache-2.0"
			(at 322.58 53.34 0)
			(effects
				(font
					(size 1.27 1.27)
					(thickness 0.15)
				)
				(justify left bottom)
				(hide yes)
			)
		)
		(property "Author" "Antmicro"
			(at 325.12 53.34 0)
			(effects
				(font
					(size 1.27 1.27)
					(thickness 0.15)
				)
				(justify left bottom)
				(hide yes)
			)
		)
		(property "Voltage" ""
			(at 327.66 53.34 0)
			(effects
				(font
					(size 1.27 1.27)
				)
				(justify left bottom)
				(hide yes)
			)
		)
		(property "Dielectric" ""
			(at 330.2 53.34 0)
			(effects
				(font
					(size 1.27 1.27)
				)
				(justify left bottom)
				(hide yes)
			)
		)
		(pin "1"
		)
		(pin "2"
		)
		(instances
			(project "artix-dc-scm"
				(path ""
					(reference "C205")
					(unit 1)
				)
			)
		)
	)
	(symbol
		(lib_id "antmicroCapacitors0402:C_10n_0402")
		(at 168.91 113.03 90)
		(unit 1)
		(exclude_from_sim no)
		(in_bom yes)
		(on_board yes)
		(dnp no)
		(property "Reference" "C215"
			(at 169.545 108.585 90)
			(effects
				(font
					(size 1.27 1.27)
				)
				(justify right)
			)
		)
		(property "Value" "C_10n_0402"
			(at 179.07 92.71 0)
			(effects
				(font
					(size 1.27 1.27)
					(thickness 0.15)
				)
				(justify left bottom)
				(hide yes)
			)
		)
		(property "Footprint" "antmicro-footprints:C_0402_1005Metric"
			(at 181.61 92.71 0)
			(effects
				(font
					(size 1.27 1.27)
					(thickness 0.15)
				)
				(justify left bottom)
				(hide yes)
			)
		)
		(property "Datasheet" "https://www.murata.com/products/productdetail?partno=GRM155R71H103KA88%23"
			(at 184.15 92.71 0)
			(effects
				(font
					(size 1.27 1.27)
					(thickness 0.15)
				)
				(justify left bottom)
				(hide yes)
			)
		)
		(property "Description" "SMD Multilayer Ceramic Capacitor, 10000 pF, 50 V, 0402 [1005 Metric], ± 10%, X7R, GRM Series"
			(at 168.91 113.03 0)
			(effects
				(font
					(size 1.27 1.27)
				)
				(hide yes)
			)
		)
		(property "Manufacturer" "Murata"
			(at 189.23 92.71 0)
			(effects
				(font
					(size 1.27 1.27)
					(thickness 0.15)
				)
				(justify left bottom)
				(hide yes)
			)
		)
		(property "MPN" "GRM155R71H103KA88D"
			(at 186.69 92.71 0)
			(effects
				(font
					(size 1.27 1.27)
					(thickness 0.15)
				)
				(justify left bottom)
				(hide yes)
			)
		)
		(property "Val" "10n"
			(at 169.545 112.395 90)
			(effects
				(font
					(size 1.27 1.27)
					(thickness 0.15)
				)
				(justify right)
			)
		)
		(property "License" "Apache-2.0"
			(at 191.77 92.71 0)
			(effects
				(font
					(size 1.27 1.27)
					(thickness 0.15)
				)
				(justify left bottom)
				(hide yes)
			)
		)
		(property "Author" "Antmicro"
			(at 194.31 92.71 0)
			(effects
				(font
					(size 1.27 1.27)
					(thickness 0.15)
				)
				(justify left bottom)
				(hide yes)
			)
		)
		(property "Voltage" "50V"
			(at 196.85 92.71 0)
			(effects
				(font
					(size 1.27 1.27)
				)
				(justify left bottom)
				(hide yes)
			)
		)
		(property "Dielectric" "X7R"
			(at 199.39 92.71 0)
			(effects
				(font
					(size 1.27 1.27)
				)
				(justify left bottom)
				(hide yes)
			)
		)
		(pin "1"
		)
		(pin "2"
		)
		(instances
			(project "artix-dc-scm"
				(path ""
					(reference "C215")
					(unit 1)
				)
			)
		)
	)
	(symbol
		(lib_id "antmicroCapacitors0402:C_4u7_0402")
		(at 152.4 113.03 90)
		(unit 1)
		(exclude_from_sim no)
		(in_bom yes)
		(on_board yes)
		(dnp no)
		(property "Reference" "C206"
			(at 153.035 108.585 90)
			(effects
				(font
					(size 1.27 1.27)
				)
				(justify right)
			)
		)
		(property "Value" "C_4u7_0402"
			(at 162.56 92.71 0)
			(effects
				(font
					(size 1.27 1.27)
					(thickness 0.15)
				)
				(justify left bottom)
				(hide yes)
			)
		)
		(property "Footprint" "antmicro-footprints:C_0402_1005Metric"
			(at 165.1 92.71 0)
			(effects
				(font
					(size 1.27 1.27)
					(thickness 0.15)
				)
				(justify left bottom)
				(hide yes)
			)
		)
		(property "Datasheet" "https://www.murata.com/products/productdetail?partno=GRM155R61A475MEAA%23"
			(at 167.64 92.71 0)
			(effects
				(font
					(size 1.27 1.27)
					(thickness 0.15)
				)
				(justify left bottom)
				(hide yes)
			)
		)
		(property "Description" "SMD Multilayer Ceramic Capacitor, 4.7 µF, 10 V, 0402 [1005 Metric], ± 20%, X5R, GRM Series"
			(at 152.4 113.03 0)
			(effects
				(font
					(size 1.27 1.27)
				)
				(hide yes)
			)
		)
		(property "Manufacturer" "Murata"
			(at 172.72 92.71 0)
			(effects
				(font
					(size 1.27 1.27)
					(thickness 0.15)
				)
				(justify left bottom)
				(hide yes)
			)
		)
		(property "MPN" "GRM155R61A475MEAAD"
			(at 170.18 92.71 0)
			(effects
				(font
					(size 1.27 1.27)
					(thickness 0.15)
				)
				(justify left bottom)
				(hide yes)
			)
		)
		(property "Val" "4u7"
			(at 153.035 112.395 90)
			(effects
				(font
					(size 1.27 1.27)
					(thickness 0.15)
				)
				(justify right)
			)
		)
		(property "License" "Apache-2.0"
			(at 175.26 92.71 0)
			(effects
				(font
					(size 1.27 1.27)
					(thickness 0.15)
				)
				(justify left bottom)
				(hide yes)
			)
		)
		(property "Author" "Antmicro"
			(at 177.8 92.71 0)
			(effects
				(font
					(size 1.27 1.27)
					(thickness 0.15)
				)
				(justify left bottom)
				(hide yes)
			)
		)
		(property "Voltage" ""
			(at 180.34 92.71 0)
			(effects
				(font
					(size 1.27 1.27)
				)
				(justify left bottom)
				(hide yes)
			)
		)
		(property "Dielectric" ""
			(at 182.88 92.71 0)
			(effects
				(font
					(size 1.27 1.27)
				)
				(justify left bottom)
				(hide yes)
			)
		)
		(pin "1"
		)
		(pin "2"
		)
		(instances
			(project "artix-dc-scm"
				(path ""
					(reference "C206")
					(unit 1)
				)
			)
		)
	)
	(symbol
		(lib_id "antmicroCapacitors0402:C_4u7_0402")
		(at 144.78 92.71 90)
		(unit 1)
		(exclude_from_sim no)
		(in_bom yes)
		(on_board yes)
		(dnp no)
		(property "Reference" "C198"
			(at 145.415 88.265 90)
			(effects
				(font
					(size 1.27 1.27)
				)
				(justify right)
			)
		)
		(property "Value" "C_4u7_0402"
			(at 154.94 72.39 0)
			(effects
				(font
					(size 1.27 1.27)
					(thickness 0.15)
				)
				(justify left bottom)
				(hide yes)
			)
		)
		(property "Footprint" "antmicro-footprints:C_0402_1005Metric"
			(at 157.48 72.39 0)
			(effects
				(font
					(size 1.27 1.27)
					(thickness 0.15)
				)
				(justify left bottom)
				(hide yes)
			)
		)
		(property "Datasheet" "https://www.murata.com/products/productdetail?partno=GRM155R61A475MEAA%23"
			(at 160.02 72.39 0)
			(effects
				(font
					(size 1.27 1.27)
					(thickness 0.15)
				)
				(justify left bottom)
				(hide yes)
			)
		)
		(property "Description" "SMD Multilayer Ceramic Capacitor, 4.7 µF, 10 V, 0402 [1005 Metric], ± 20%, X5R, GRM Series"
			(at 144.78 92.71 0)
			(effects
				(font
					(size 1.27 1.27)
				)
				(hide yes)
			)
		)
		(property "Manufacturer" "Murata"
			(at 165.1 72.39 0)
			(effects
				(font
					(size 1.27 1.27)
					(thickness 0.15)
				)
				(justify left bottom)
				(hide yes)
			)
		)
		(property "MPN" "GRM155R61A475MEAAD"
			(at 162.56 72.39 0)
			(effects
				(font
					(size 1.27 1.27)
					(thickness 0.15)
				)
				(justify left bottom)
				(hide yes)
			)
		)
		(property "Val" "4u7"
			(at 145.415 92.075 90)
			(effects
				(font
					(size 1.27 1.27)
					(thickness 0.15)
				)
				(justify right)
			)
		)
		(property "License" "Apache-2.0"
			(at 167.64 72.39 0)
			(effects
				(font
					(size 1.27 1.27)
					(thickness 0.15)
				)
				(justify left bottom)
				(hide yes)
			)
		)
		(property "Author" "Antmicro"
			(at 170.18 72.39 0)
			(effects
				(font
					(size 1.27 1.27)
					(thickness 0.15)
				)
				(justify left bottom)
				(hide yes)
			)
		)
		(property "Voltage" ""
			(at 172.72 72.39 0)
			(effects
				(font
					(size 1.27 1.27)
				)
				(justify left bottom)
				(hide yes)
			)
		)
		(property "Dielectric" ""
			(at 175.26 72.39 0)
			(effects
				(font
					(size 1.27 1.27)
				)
				(justify left bottom)
				(hide yes)
			)
		)
		(pin "1"
		)
		(pin "2"
		)
		(instances
			(project "artix-dc-scm"
				(path ""
					(reference "C198")
					(unit 1)
				)
			)
		)
	)
	(symbol
		(lib_id "antmicroCapacitors0402:C_470n_0402")
		(at 152.4 92.71 90)
		(unit 1)
		(exclude_from_sim no)
		(in_bom yes)
		(on_board yes)
		(dnp no)
		(property "Reference" "C202"
			(at 153.035 88.265 90)
			(effects
				(font
					(size 1.27 1.27)
				)
				(justify right)
			)
		)
		(property "Value" "C_470n_0402"
			(at 162.56 72.39 0)
			(effects
				(font
					(size 1.27 1.27)
					(thickness 0.15)
				)
				(justify left bottom)
				(hide yes)
			)
		)
		(property "Footprint" "antmicro-footprints:C_0402_1005Metric"
			(at 165.1 72.39 0)
			(effects
				(font
					(size 1.27 1.27)
					(thickness 0.15)
				)
				(justify left bottom)
				(hide yes)
			)
		)
		(property "Datasheet" "https://product.tdk.com/en/search/capacitor/ceramic/mlcc/info?part_no=C1005X5R1E474M050BB"
			(at 167.64 72.39 0)
			(effects
				(font
					(size 1.27 1.27)
					(thickness 0.15)
				)
				(justify left bottom)
				(hide yes)
			)
		)
		(property "Description" "SMD Multilayer Ceramic Capacitor, 0.47 µF, 25 V, 0402 [1005 Metric], ± 20%, X5R, C"
			(at 152.4 92.71 0)
			(effects
				(font
					(size 1.27 1.27)
				)
				(hide yes)
			)
		)
		(property "Manufacturer" "TDK"
			(at 172.72 72.39 0)
			(effects
				(font
					(size 1.27 1.27)
					(thickness 0.15)
				)
				(justify left bottom)
				(hide yes)
			)
		)
		(property "MPN" "C1005X5R1E474M050BB"
			(at 170.18 72.39 0)
			(effects
				(font
					(size 1.27 1.27)
					(thickness 0.15)
				)
				(justify left bottom)
				(hide yes)
			)
		)
		(property "Val" "470n"
			(at 153.035 92.075 90)
			(effects
				(font
					(size 1.27 1.27)
					(thickness 0.15)
				)
				(justify right)
			)
		)
		(property "License" "Apache-2.0"
			(at 175.26 72.39 0)
			(effects
				(font
					(size 1.27 1.27)
					(thickness 0.15)
				)
				(justify left bottom)
				(hide yes)
			)
		)
		(property "Author" "Antmicro"
			(at 177.8 72.39 0)
			(effects
				(font
					(size 1.27 1.27)
					(thickness 0.15)
				)
				(justify left bottom)
				(hide yes)
			)
		)
		(property "Voltage" ""
			(at 180.34 72.39 0)
			(effects
				(font
					(size 1.27 1.27)
				)
				(justify left bottom)
				(hide yes)
			)
		)
		(property "Dielectric" ""
			(at 182.88 72.39 0)
			(effects
				(font
					(size 1.27 1.27)
				)
				(justify left bottom)
				(hide yes)
			)
		)
		(pin "1"
		)
		(pin "2"
		)
		(instances
			(project "artix-dc-scm"
				(path ""
					(reference "C202")
					(unit 1)
				)
			)
		)
	)
	(symbol
		(lib_id "antmicroCapacitors0402:C_10n_0402")
		(at 168.91 92.71 90)
		(unit 1)
		(exclude_from_sim no)
		(in_bom yes)
		(on_board yes)
		(dnp no)
		(property "Reference" "C212"
			(at 169.545 88.265 90)
			(effects
				(font
					(size 1.27 1.27)
				)
				(justify right)
			)
		)
		(property "Value" "C_10n_0402"
			(at 179.07 72.39 0)
			(effects
				(font
					(size 1.27 1.27)
					(thickness 0.15)
				)
				(justify left bottom)
				(hide yes)
			)
		)
		(property "Footprint" "antmicro-footprints:C_0402_1005Metric"
			(at 181.61 72.39 0)
			(effects
				(font
					(size 1.27 1.27)
					(thickness 0.15)
				)
				(justify left bottom)
				(hide yes)
			)
		)
		(property "Datasheet" "https://www.murata.com/products/productdetail?partno=GRM155R71H103KA88%23"
			(at 184.15 72.39 0)
			(effects
				(font
					(size 1.27 1.27)
					(thickness 0.15)
				)
				(justify left bottom)
				(hide yes)
			)
		)
		(property "Description" "SMD Multilayer Ceramic Capacitor, 10000 pF, 50 V, 0402 [1005 Metric], ± 10%, X7R, GRM Series"
			(at 168.91 92.71 0)
			(effects
				(font
					(size 1.27 1.27)
				)
				(hide yes)
			)
		)
		(property "Manufacturer" "Murata"
			(at 189.23 72.39 0)
			(effects
				(font
					(size 1.27 1.27)
					(thickness 0.15)
				)
				(justify left bottom)
				(hide yes)
			)
		)
		(property "MPN" "GRM155R71H103KA88D"
			(at 186.69 72.39 0)
			(effects
				(font
					(size 1.27 1.27)
					(thickness 0.15)
				)
				(justify left bottom)
				(hide yes)
			)
		)
		(property "Val" "10n"
			(at 169.545 92.075 90)
			(effects
				(font
					(size 1.27 1.27)
					(thickness 0.15)
				)
				(justify right)
			)
		)
		(property "License" "Apache-2.0"
			(at 191.77 72.39 0)
			(effects
				(font
					(size 1.27 1.27)
					(thickness 0.15)
				)
				(justify left bottom)
				(hide yes)
			)
		)
		(property "Author" "Antmicro"
			(at 194.31 72.39 0)
			(effects
				(font
					(size 1.27 1.27)
					(thickness 0.15)
				)
				(justify left bottom)
				(hide yes)
			)
		)
		(property "Voltage" "50V"
			(at 196.85 72.39 0)
			(effects
				(font
					(size 1.27 1.27)
				)
				(justify left bottom)
				(hide yes)
			)
		)
		(property "Dielectric" "X7R"
			(at 199.39 72.39 0)
			(effects
				(font
					(size 1.27 1.27)
				)
				(justify left bottom)
				(hide yes)
			)
		)
		(pin "1"
		)
		(pin "2"
		)
		(instances
			(project "artix-dc-scm"
				(path ""
					(reference "C212")
					(unit 1)
				)
			)
		)
	)
	(symbol
		(lib_id "antmicroCapacitors0402:C_10n_0402")
		(at 177.8 92.71 90)
		(unit 1)
		(exclude_from_sim no)
		(in_bom yes)
		(on_board yes)
		(dnp no)
		(property "Reference" "C216"
			(at 178.435 88.265 90)
			(effects
				(font
					(size 1.27 1.27)
				)
				(justify right)
			)
		)
		(property "Value" "C_10n_0402"
			(at 187.96 72.39 0)
			(effects
				(font
					(size 1.27 1.27)
					(thickness 0.15)
				)
				(justify left bottom)
				(hide yes)
			)
		)
		(property "Footprint" "antmicro-footprints:C_0402_1005Metric"
			(at 190.5 72.39 0)
			(effects
				(font
					(size 1.27 1.27)
					(thickness 0.15)
				)
				(justify left bottom)
				(hide yes)
			)
		)
		(property "Datasheet" "https://www.murata.com/products/productdetail?partno=GRM155R71H103KA88%23"
			(at 193.04 72.39 0)
			(effects
				(font
					(size 1.27 1.27)
					(thickness 0.15)
				)
				(justify left bottom)
				(hide yes)
			)
		)
		(property "Description" "SMD Multilayer Ceramic Capacitor, 10000 pF, 50 V, 0402 [1005 Metric], ± 10%, X7R, GRM Series"
			(at 177.8 92.71 0)
			(effects
				(font
					(size 1.27 1.27)
				)
				(hide yes)
			)
		)
		(property "Manufacturer" "Murata"
			(at 198.12 72.39 0)
			(effects
				(font
					(size 1.27 1.27)
					(thickness 0.15)
				)
				(justify left bottom)
				(hide yes)
			)
		)
		(property "MPN" "GRM155R71H103KA88D"
			(at 195.58 72.39 0)
			(effects
				(font
					(size 1.27 1.27)
					(thickness 0.15)
				)
				(justify left bottom)
				(hide yes)
			)
		)
		(property "Val" "10n"
			(at 178.435 92.075 90)
			(effects
				(font
					(size 1.27 1.27)
					(thickness 0.15)
				)
				(justify right)
			)
		)
		(property "License" "Apache-2.0"
			(at 200.66 72.39 0)
			(effects
				(font
					(size 1.27 1.27)
					(thickness 0.15)
				)
				(justify left bottom)
				(hide yes)
			)
		)
		(property "Author" "Antmicro"
			(at 203.2 72.39 0)
			(effects
				(font
					(size 1.27 1.27)
					(thickness 0.15)
				)
				(justify left bottom)
				(hide yes)
			)
		)
		(property "Voltage" "50V"
			(at 205.74 72.39 0)
			(effects
				(font
					(size 1.27 1.27)
				)
				(justify left bottom)
				(hide yes)
			)
		)
		(property "Dielectric" "X7R"
			(at 208.28 72.39 0)
			(effects
				(font
					(size 1.27 1.27)
				)
				(justify left bottom)
				(hide yes)
			)
		)
		(pin "1"
		)
		(pin "2"
		)
		(instances
			(project "artix-dc-scm"
				(path ""
					(reference "C216")
					(unit 1)
				)
			)
		)
	)
	(symbol
		(lib_id "antmicroCapacitors0402:C_10n_0402")
		(at 161.29 92.71 90)
		(unit 1)
		(exclude_from_sim no)
		(in_bom yes)
		(on_board yes)
		(dnp no)
		(property "Reference" "C207"
			(at 161.925 88.265 90)
			(effects
				(font
					(size 1.27 1.27)
				)
				(justify right)
			)
		)
		(property "Value" "C_10n_0402"
			(at 171.45 72.39 0)
			(effects
				(font
					(size 1.27 1.27)
					(thickness 0.15)
				)
				(justify left bottom)
				(hide yes)
			)
		)
		(property "Footprint" "antmicro-footprints:C_0402_1005Metric"
			(at 173.99 72.39 0)
			(effects
				(font
					(size 1.27 1.27)
					(thickness 0.15)
				)
				(justify left bottom)
				(hide yes)
			)
		)
		(property "Datasheet" "https://www.murata.com/products/productdetail?partno=GRM155R71H103KA88%23"
			(at 176.53 72.39 0)
			(effects
				(font
					(size 1.27 1.27)
					(thickness 0.15)
				)
				(justify left bottom)
				(hide yes)
			)
		)
		(property "Description" "SMD Multilayer Ceramic Capacitor, 10000 pF, 50 V, 0402 [1005 Metric], ± 10%, X7R, GRM Series"
			(at 161.29 92.71 0)
			(effects
				(font
					(size 1.27 1.27)
				)
				(hide yes)
			)
		)
		(property "Manufacturer" "Murata"
			(at 181.61 72.39 0)
			(effects
				(font
					(size 1.27 1.27)
					(thickness 0.15)
				)
				(justify left bottom)
				(hide yes)
			)
		)
		(property "MPN" "GRM155R71H103KA88D"
			(at 179.07 72.39 0)
			(effects
				(font
					(size 1.27 1.27)
					(thickness 0.15)
				)
				(justify left bottom)
				(hide yes)
			)
		)
		(property "Val" "10n"
			(at 161.925 92.075 90)
			(effects
				(font
					(size 1.27 1.27)
					(thickness 0.15)
				)
				(justify right)
			)
		)
		(property "License" "Apache-2.0"
			(at 184.15 72.39 0)
			(effects
				(font
					(size 1.27 1.27)
					(thickness 0.15)
				)
				(justify left bottom)
				(hide yes)
			)
		)
		(property "Author" "Antmicro"
			(at 186.69 72.39 0)
			(effects
				(font
					(size 1.27 1.27)
					(thickness 0.15)
				)
				(justify left bottom)
				(hide yes)
			)
		)
		(property "Voltage" "50V"
			(at 189.23 72.39 0)
			(effects
				(font
					(size 1.27 1.27)
				)
				(justify left bottom)
				(hide yes)
			)
		)
		(property "Dielectric" "X7R"
			(at 191.77 72.39 0)
			(effects
				(font
					(size 1.27 1.27)
				)
				(justify left bottom)
				(hide yes)
			)
		)
		(pin "1"
		)
		(pin "2"
		)
		(instances
			(project "artix-dc-scm"
				(path ""
					(reference "C207")
					(unit 1)
				)
			)
		)
	)
	(symbol
		(lib_id "antmicroInterfaceControllers:KSZ9031RNXCA")
		(at 196.85 114.3 0)
		(unit 1)
		(exclude_from_sim no)
		(in_bom yes)
		(on_board yes)
		(dnp no)
		(fields_autoplaced yes)
		(property "Reference" "U20"
			(at 219.075 106.68 0)
			(effects
				(font
					(size 1.27 1.27)
				)
			)
		)
		(property "Value" "KSZ9031RNXCA"
			(at 219.075 109.22 0)
			(effects
				(font
					(size 1.27 1.27)
					(thickness 0.15)
				)
			)
		)
		(property "Footprint" "antmicro-footprints:QFN-48-1EP_7x7x0.9mm_P0.5mm_EP3.5x3.5mm"
			(at 273.05 124.46 0)
			(effects
				(font
					(size 1.27 1.27)
					(thickness 0.15)
				)
				(justify left bottom)
				(hide yes)
			)
		)
		(property "Datasheet" "http://ww1.microchip.com/downloads/en/DeviceDoc/00002117F.pdf"
			(at 273.05 127 0)
			(effects
				(font
					(size 1.27 1.27)
					(thickness 0.15)
				)
				(justify left bottom)
				(hide yes)
			)
		)
		(property "Description" "Ethernet Controller, 1000 Mbps, IEEE 802.3, 1.14 V, 3.465 V, QFN, 48 Pins"
			(at 196.85 114.3 0)
			(effects
				(font
					(size 1.27 1.27)
				)
				(hide yes)
			)
		)
		(property "Manufacturer" "Microchip Technology"
			(at 273.05 129.54 0)
			(effects
				(font
					(size 1.27 1.27)
					(thickness 0.15)
				)
				(justify left bottom)
				(hide yes)
			)
		)
		(property "MPN" "KSZ9031RNXCA"
			(at 273.05 132.08 0)
			(effects
				(font
					(size 1.27 1.27)
					(thickness 0.15)
				)
				(justify left bottom)
				(hide yes)
			)
		)
		(property "Author" "Antmicro"
			(at 273.05 134.62 0)
			(effects
				(font
					(size 1.27 1.27)
					(thickness 0.15)
				)
				(justify left bottom)
				(hide yes)
			)
		)
		(property "License" "Apache-2.0"
			(at 273.05 137.16 0)
			(effects
				(font
					(size 1.27 1.27)
					(thickness 0.15)
				)
				(justify left bottom)
				(hide yes)
			)
		)
		(pin "1"
		)
		(pin "10"
		)
		(pin "11"
		)
		(pin "12"
		)
		(pin "13"
		)
		(pin "14"
		)
		(pin "15"
		)
		(pin "16"
		)
		(pin "17"
		)
		(pin "18"
		)
		(pin "19"
		)
		(pin "2"
		)
		(pin "20"
		)
		(pin "21"
		)
		(pin "22"
		)
		(pin "23"
		)
		(pin "24"
		)
		(pin "25"
		)
		(pin "26"
		)
		(pin "27"
		)
		(pin "28"
		)
		(pin "29"
		)
		(pin "3"
		)
		(pin "30"
		)
		(pin "31"
		)
		(pin "32"
		)
		(pin "33"
		)
		(pin "34"
		)
		(pin "35"
		)
		(pin "36"
		)
		(pin "37"
		)
		(pin "38"
		)
		(pin "39"
		)
		(pin "4"
		)
		(pin "40"
		)
		(pin "41"
		)
		(pin "42"
		)
		(pin "43"
		)
		(pin "44"
		)
		(pin "45"
		)
		(pin "46"
		)
		(pin "47"
		)
		(pin "48"
		)
		(pin "49"
		)
		(pin "5"
		)
		(pin "6"
		)
		(pin "7"
		)
		(pin "8"
		)
		(pin "9"
		)
		(instances
			(project "artix-dc-scm"
				(path ""
					(reference "U20")
					(unit 1)
				)
			)
		)
	)
	(symbol
		(lib_id "antmicroFerriteBeadsandChips:FB_120Z_2A_Murata-BLM18PG_0603")
		(at 312.42 86.36 0)
		(unit 1)
		(exclude_from_sim no)
		(in_bom yes)
		(on_board yes)
		(dnp no)
		(fields_autoplaced yes)
		(property "Reference" "FB6"
			(at 314.9219 90.17 0)
			(effects
				(font
					(size 1.27 1.27)
				)
			)
		)
		(property "Value" "FB_120Z_2A_Murata-BLM18PG_0603"
			(at 326.39 88.9 0)
			(effects
				(font
					(size 1.27 1.27)
					(thickness 0.15)
				)
				(justify left bottom)
				(hide yes)
			)
		)
		(property "Footprint" "antmicro-footprints:FB_0603_1608Metric"
			(at 326.39 91.44 0)
			(effects
				(font
					(size 1.27 1.27)
					(thickness 0.15)
				)
				(justify left bottom)
				(hide yes)
			)
		)
		(property "Datasheet" "https://www.murata.com/en-us/products/productdata/8796738650142/ENFA0003.pdf"
			(at 326.39 93.98 0)
			(effects
				(font
					(size 1.27 1.27)
					(thickness 0.15)
				)
				(justify left bottom)
				(hide yes)
			)
		)
		(property "Description" "Ferrite Bead, 0603 [1608 Metric], 120 ohm, 2 A, BLM18P, 0.05 ohm, ± 25%, DC power line"
			(at 312.42 86.36 0)
			(effects
				(font
					(size 1.27 1.27)
				)
				(hide yes)
			)
		)
		(property "MPN" "BLM18PG121SN1D"
			(at 314.9219 92.71 0)
			(effects
				(font
					(size 1.27 1.27)
					(thickness 0.15)
				)
			)
		)
		(property "Manufacturer" "Murata"
			(at 326.39 99.06 0)
			(effects
				(font
					(size 1.27 1.27)
					(thickness 0.15)
				)
				(justify left bottom)
				(hide yes)
			)
		)
		(property "Author" "Antmicro"
			(at 326.39 101.6 0)
			(effects
				(font
					(size 1.27 1.27)
					(thickness 0.15)
				)
				(justify left bottom)
				(hide yes)
			)
		)
		(property "License" "Apache-2.0"
			(at 326.39 104.14 0)
			(effects
				(font
					(size 1.27 1.27)
					(thickness 0.15)
				)
				(justify left bottom)
				(hide yes)
			)
		)
		(property "Val" "120Z/2A"
			(at 314.9219 95.25 0)
			(effects
				(font
					(size 1.27 1.27)
				)
			)
		)
		(property "Current" ""
			(at 332.74 109.22 0)
			(effects
				(font
					(size 1.27 1.27)
					(thickness 0.15)
				)
				(justify left bottom)
				(hide yes)
			)
		)
		(pin "1"
		)
		(pin "2"
		)
		(instances
			(project "artix-dc-scm"
				(path ""
					(reference "FB6")
					(unit 1)
				)
			)
		)
	)
	(symbol
		(lib_id "antmicroFerriteBeadsandChips:FB_120Z_2A_Murata-BLM18PG_0603")
		(at 312.42 106.68 0)
		(unit 1)
		(exclude_from_sim no)
		(in_bom yes)
		(on_board yes)
		(dnp no)
		(property "Reference" "FB5"
			(at 314.96 110.49 0)
			(effects
				(font
					(size 1.27 1.27)
				)
			)
		)
		(property "Value" "FB_120Z_2A_Murata-BLM18PG_0603"
			(at 314.9219 102.87 0)
			(effects
				(font
					(size 1.27 1.27)
					(thickness 0.15)
				)
				(hide yes)
			)
		)
		(property "Footprint" "antmicro-footprints:FB_0603_1608Metric"
			(at 326.39 111.76 0)
			(effects
				(font
					(size 1.27 1.27)
					(thickness 0.15)
				)
				(justify left bottom)
				(hide yes)
			)
		)
		(property "Datasheet" "https://www.murata.com/en-us/products/productdata/8796738650142/ENFA0003.pdf"
			(at 326.39 114.3 0)
			(effects
				(font
					(size 1.27 1.27)
					(thickness 0.15)
				)
				(justify left bottom)
				(hide yes)
			)
		)
		(property "Description" "Ferrite Bead, 0603 [1608 Metric], 120 ohm, 2 A, BLM18P, 0.05 ohm, ± 25%, DC power line"
			(at 312.42 106.68 0)
			(effects
				(font
					(size 1.27 1.27)
				)
				(hide yes)
			)
		)
		(property "MPN" "BLM18PG121SN1D"
			(at 314.96 113.03 0)
			(effects
				(font
					(size 1.27 1.27)
					(thickness 0.15)
				)
			)
		)
		(property "Manufacturer" "Murata"
			(at 326.39 119.38 0)
			(effects
				(font
					(size 1.27 1.27)
					(thickness 0.15)
				)
				(justify left bottom)
				(hide yes)
			)
		)
		(property "Author" "Antmicro"
			(at 326.39 121.92 0)
			(effects
				(font
					(size 1.27 1.27)
					(thickness 0.15)
				)
				(justify left bottom)
				(hide yes)
			)
		)
		(property "License" "Apache-2.0"
			(at 326.39 124.46 0)
			(effects
				(font
					(size 1.27 1.27)
					(thickness 0.15)
				)
				(justify left bottom)
				(hide yes)
			)
		)
		(property "Val" "120Z/2A"
			(at 314.96 115.57 0)
			(effects
				(font
					(size 1.27 1.27)
				)
			)
		)
		(property "Current" ""
			(at 332.74 129.54 0)
			(effects
				(font
					(size 1.27 1.27)
					(thickness 0.15)
				)
				(justify left bottom)
				(hide yes)
			)
		)
		(pin "1"
		)
		(pin "2"
		)
		(instances
			(project "artix-dc-scm"
				(path ""
					(reference "FB5")
					(unit 1)
				)
			)
		)
	)
	(symbol
		(lib_id "antmicroFerriteBeadsandChips:FB_120Z_2A_Murata-BLM18PG_0603")
		(at 135.89 106.68 0)
		(unit 1)
		(exclude_from_sim no)
		(in_bom yes)
		(on_board yes)
		(dnp no)
		(fields_autoplaced yes)
		(property "Reference" "FB4"
			(at 138.3919 110.49 0)
			(effects
				(font
					(size 1.27 1.27)
				)
			)
		)
		(property "Value" "FB_120Z_2A_Murata-BLM18PG_0603"
			(at 149.86 109.22 0)
			(effects
				(font
					(size 1.27 1.27)
					(thickness 0.15)
				)
				(justify left bottom)
				(hide yes)
			)
		)
		(property "Footprint" "antmicro-footprints:FB_0603_1608Metric"
			(at 149.86 111.76 0)
			(effects
				(font
					(size 1.27 1.27)
					(thickness 0.15)
				)
				(justify left bottom)
				(hide yes)
			)
		)
		(property "Datasheet" "https://www.murata.com/en-us/products/productdata/8796738650142/ENFA0003.pdf"
			(at 149.86 114.3 0)
			(effects
				(font
					(size 1.27 1.27)
					(thickness 0.15)
				)
				(justify left bottom)
				(hide yes)
			)
		)
		(property "Description" "Ferrite Bead, 0603 [1608 Metric], 120 ohm, 2 A, BLM18P, 0.05 ohm, ± 25%, DC power line"
			(at 135.89 106.68 0)
			(effects
				(font
					(size 1.27 1.27)
				)
				(hide yes)
			)
		)
		(property "MPN" "BLM18PG121SN1D"
			(at 138.3919 113.03 0)
			(effects
				(font
					(size 1.27 1.27)
					(thickness 0.15)
				)
			)
		)
		(property "Manufacturer" "Murata"
			(at 149.86 119.38 0)
			(effects
				(font
					(size 1.27 1.27)
					(thickness 0.15)
				)
				(justify left bottom)
				(hide yes)
			)
		)
		(property "Author" "Antmicro"
			(at 149.86 121.92 0)
			(effects
				(font
					(size 1.27 1.27)
					(thickness 0.15)
				)
				(justify left bottom)
				(hide yes)
			)
		)
		(property "License" "Apache-2.0"
			(at 149.86 124.46 0)
			(effects
				(font
					(size 1.27 1.27)
					(thickness 0.15)
				)
				(justify left bottom)
				(hide yes)
			)
		)
		(property "Val" "120Z/2A"
			(at 138.3919 115.57 0)
			(effects
				(font
					(size 1.27 1.27)
				)
			)
		)
		(property "Current" ""
			(at 156.21 129.54 0)
			(effects
				(font
					(size 1.27 1.27)
					(thickness 0.15)
				)
				(justify left bottom)
				(hide yes)
			)
		)
		(pin "1"
		)
		(pin "2"
		)
		(instances
			(project "artix-dc-scm"
				(path ""
					(reference "FB4")
					(unit 1)
				)
			)
		)
	)
	(symbol
		(lib_id "antmicroResistors0402:R_12k1_0402")
		(at 242.57 170.18 90)
		(unit 1)
		(exclude_from_sim no)
		(in_bom yes)
		(on_board yes)
		(dnp no)
		(property "Reference" "R159"
			(at 243.84 166.37 90)
			(effects
				(font
					(size 1.27 1.27)
				)
				(justify right)
			)
		)
		(property "Value" "R_12k1_0402"
			(at 255.27 149.86 0)
			(effects
				(font
					(size 1.27 1.27)
					(thickness 0.15)
				)
				(justify left bottom)
				(hide yes)
			)
		)
		(property "Footprint" "antmicro-footprints:R_0402_1005Metric"
			(at 257.81 149.86 0)
			(effects
				(font
					(size 1.27 1.27)
					(thickness 0.15)
				)
				(justify left bottom)
				(hide yes)
			)
		)
		(property "Datasheet" "https://www.bourns.com/docs/product-datasheets/cr.pdf"
			(at 260.35 149.86 0)
			(effects
				(font
					(size 1.27 1.27)
					(thickness 0.15)
				)
				(justify left bottom)
				(hide yes)
			)
		)
		(property "Description" "SMD Chip Resistor, 12.1 kohm, ± 1%, 62.5 mW, 0402 [1005 Metric], Thick Film, General Purpose"
			(at 242.57 170.18 0)
			(effects
				(font
					(size 1.27 1.27)
				)
				(hide yes)
			)
		)
		(property "Manufacturer" "Bourns"
			(at 265.43 149.86 0)
			(effects
				(font
					(size 1.27 1.27)
					(thickness 0.15)
				)
				(justify left bottom)
				(hide yes)
			)
		)
		(property "MPN" "CR0402-FX-1212GLF"
			(at 262.89 149.86 0)
			(effects
				(font
					(size 1.27 1.27)
					(thickness 0.15)
				)
				(justify left bottom)
				(hide yes)
			)
		)
		(property "Val" "12k1"
			(at 243.84 169.5449 90)
			(effects
				(font
					(size 1.27 1.27)
					(thickness 0.15)
				)
				(justify right)
			)
		)
		(property "License" "Apache-2.0"
			(at 267.97 149.86 0)
			(effects
				(font
					(size 1.27 1.27)
					(thickness 0.15)
				)
				(justify left bottom)
				(hide yes)
			)
		)
		(property "Author" "Antmicro"
			(at 270.51 149.86 0)
			(effects
				(font
					(size 1.27 1.27)
					(thickness 0.15)
				)
				(justify left bottom)
				(hide yes)
			)
		)
		(property "Tolerance" "1%"
			(at 252.73 149.86 0)
			(effects
				(font
					(size 1.27 1.27)
				)
				(justify left bottom)
				(hide yes)
			)
		)
		(pin "1"
		)
		(pin "2"
		)
		(instances
			(project "artix-dc-scm"
				(path ""
					(reference "R159")
					(unit 1)
				)
			)
		)
	)
	(symbol
		(lib_id "antmicroResistors0402:R_4k7_0402")
		(at 132.08 134.62 90)
		(unit 1)
		(exclude_from_sim no)
		(in_bom yes)
		(on_board yes)
		(dnp no)
		(property "Reference" "R155"
			(at 133.35 130.81 90)
			(effects
				(font
					(size 1.27 1.27)
				)
				(justify right)
			)
		)
		(property "Value" "R_4k7_0402"
			(at 144.78 114.3 0)
			(effects
				(font
					(size 1.27 1.27)
					(thickness 0.15)
				)
				(justify left bottom)
				(hide yes)
			)
		)
		(property "Footprint" "antmicro-footprints:R_0402_1005Metric"
			(at 147.32 114.3 0)
			(effects
				(font
					(size 1.27 1.27)
					(thickness 0.15)
				)
				(justify left bottom)
				(hide yes)
			)
		)
		(property "Datasheet" "https://www.bourns.com/docs/product-datasheets/cr.pdf"
			(at 149.86 114.3 0)
			(effects
				(font
					(size 1.27 1.27)
					(thickness 0.15)
				)
				(justify left bottom)
				(hide yes)
			)
		)
		(property "Description" "SMD Chip Resistor, 4.7 kohm, ± 1%, 62.5 mW, 0402 [1005 Metric], Thick Film, General Purpose"
			(at 132.08 134.62 0)
			(effects
				(font
					(size 1.27 1.27)
				)
				(hide yes)
			)
		)
		(property "Manufacturer" "Bourns"
			(at 154.94 114.3 0)
			(effects
				(font
					(size 1.27 1.27)
					(thickness 0.15)
				)
				(justify left bottom)
				(hide yes)
			)
		)
		(property "MPN" "CR0402-FX-4701GLF"
			(at 152.4 114.3 0)
			(effects
				(font
					(size 1.27 1.27)
					(thickness 0.15)
				)
				(justify left bottom)
				(hide yes)
			)
		)
		(property "Val" "4k7"
			(at 133.35 133.35 90)
			(effects
				(font
					(size 1.27 1.27)
					(thickness 0.15)
				)
				(justify right)
			)
		)
		(property "License" "Apache-2.0"
			(at 157.48 114.3 0)
			(effects
				(font
					(size 1.27 1.27)
					(thickness 0.15)
				)
				(justify left bottom)
				(hide yes)
			)
		)
		(property "Author" "Antmicro"
			(at 160.02 114.3 0)
			(effects
				(font
					(size 1.27 1.27)
					(thickness 0.15)
				)
				(justify left bottom)
				(hide yes)
			)
		)
		(property "Tolerance" "1%"
			(at 142.24 114.3 0)
			(effects
				(font
					(size 1.27 1.27)
				)
				(justify left bottom)
				(hide yes)
			)
		)
		(pin "1"
		)
		(pin "2"
		)
		(instances
			(project "artix-dc-scm"
				(path ""
					(reference "R155")
					(unit 1)
				)
			)
		)
	)
	(symbol
		(lib_id "antmicroCapacitors0402:C_22p_0402")
		(at 191.77 190.5 270)
		(mirror x)
		(unit 1)
		(exclude_from_sim no)
		(in_bom yes)
		(on_board yes)
		(dnp no)
		(property "Reference" "C176"
			(at 192.405 186.055 90)
			(effects
				(font
					(size 1.27 1.27)
				)
				(justify left)
			)
		)
		(property "Value" "C_22p_0402"
			(at 181.61 170.18 0)
			(effects
				(font
					(size 1.27 1.27)
					(thickness 0.15)
				)
				(justify left bottom)
				(hide yes)
			)
		)
		(property "Footprint" "antmicro-footprints:C_0402_1005Metric"
			(at 179.07 170.18 0)
			(effects
				(font
					(size 1.27 1.27)
					(thickness 0.15)
				)
				(justify left bottom)
				(hide yes)
			)
		)
		(property "Datasheet" "https://www.yageo.com/en/Chart/Download/pdf/CC0402JRNPO9BN220"
			(at 176.53 170.18 0)
			(effects
				(font
					(size 1.27 1.27)
					(thickness 0.15)
				)
				(justify left bottom)
				(hide yes)
			)
		)
		(property "Description" "SMD Multilayer Ceramic Capacitor, 22 pF, 50 V, 0402 [1005 Metric], ± 5%, C0G / NP0, CC Series"
			(at 191.77 190.5 0)
			(effects
				(font
					(size 1.27 1.27)
				)
				(hide yes)
			)
		)
		(property "Manufacturer" "YAGEO"
			(at 171.45 170.18 0)
			(effects
				(font
					(size 1.27 1.27)
					(thickness 0.15)
				)
				(justify left bottom)
				(hide yes)
			)
		)
		(property "MPN" "CC0402JRNPO9BN220"
			(at 173.99 170.18 0)
			(effects
				(font
					(size 1.27 1.27)
					(thickness 0.15)
				)
				(justify left bottom)
				(hide yes)
			)
		)
		(property "Val" "22p"
			(at 192.405 189.865 90)
			(effects
				(font
					(size 1.27 1.27)
					(thickness 0.15)
				)
				(justify left)
			)
		)
		(property "License" "Apache-2.0"
			(at 168.91 170.18 0)
			(effects
				(font
					(size 1.27 1.27)
					(thickness 0.15)
				)
				(justify left bottom)
				(hide yes)
			)
		)
		(property "Author" "Antmicro"
			(at 166.37 170.18 0)
			(effects
				(font
					(size 1.27 1.27)
					(thickness 0.15)
				)
				(justify left bottom)
				(hide yes)
			)
		)
		(property "Voltage" ""
			(at 163.83 170.18 0)
			(effects
				(font
					(size 1.27 1.27)
				)
				(justify left bottom)
				(hide yes)
			)
		)
		(property "Dielectric" ""
			(at 161.29 170.18 0)
			(effects
				(font
					(size 1.27 1.27)
				)
				(justify left bottom)
				(hide yes)
			)
		)
		(pin "1"
		)
		(pin "2"
		)
		(instances
			(project "artix-dc-scm"
				(path ""
					(reference "C176")
					(unit 1)
				)
			)
		)
	)
	(symbol
		(lib_id "antmicroResistors0402:R_1M8_0402")
		(at 187.96 173.99 0)
		(mirror y)
		(unit 1)
		(exclude_from_sim no)
		(in_bom yes)
		(on_board yes)
		(dnp no)
		(property "Reference" "R194"
			(at 190.5 172.72 0)
			(effects
				(font
					(size 1.27 1.27)
				)
			)
		)
		(property "Value" "R_1M8_0402"
			(at 167.64 186.69 0)
			(effects
				(font
					(size 1.27 1.27)
					(thickness 0.15)
				)
				(justify left bottom)
				(hide yes)
			)
		)
		(property "Footprint" "antmicro-footprints:R_0402_1005Metric"
			(at 167.64 189.23 0)
			(effects
				(font
					(size 1.27 1.27)
					(thickness 0.15)
				)
				(justify left bottom)
				(hide yes)
			)
		)
		(property "Datasheet" "https://www.bourns.com/docs/product-datasheets/cr.pdf"
			(at 167.64 191.77 0)
			(effects
				(font
					(size 1.27 1.27)
					(thickness 0.15)
				)
				(justify left bottom)
				(hide yes)
			)
		)
		(property "Description" "SMD Chip Resistor"
			(at 187.96 173.99 0)
			(effects
				(font
					(size 1.27 1.27)
				)
				(hide yes)
			)
		)
		(property "Manufacturer" "Bourns"
			(at 167.64 196.85 0)
			(effects
				(font
					(size 1.27 1.27)
					(thickness 0.15)
				)
				(justify left bottom)
				(hide yes)
			)
		)
		(property "MPN" "CR0402-FX-1804GLF"
			(at 167.64 194.31 0)
			(effects
				(font
					(size 1.27 1.27)
					(thickness 0.15)
				)
				(justify left bottom)
				(hide yes)
			)
		)
		(property "Val" "1M8"
			(at 182.88 173.99 0)
			(effects
				(font
					(size 1.27 1.27)
					(thickness 0.15)
				)
				(justify left bottom)
			)
		)
		(property "License" "Apache-2.0"
			(at 167.64 199.39 0)
			(effects
				(font
					(size 1.27 1.27)
					(thickness 0.15)
				)
				(justify left bottom)
				(hide yes)
			)
		)
		(property "Author" "Antmicro"
			(at 167.64 201.93 0)
			(effects
				(font
					(size 1.27 1.27)
					(thickness 0.15)
				)
				(justify left bottom)
				(hide yes)
			)
		)
		(property "Tolerance" "1%"
			(at 167.64 184.15 0)
			(effects
				(font
					(size 1.27 1.27)
				)
				(justify left bottom)
				(hide yes)
			)
		)
		(pin "1"
		)
		(pin "2"
		)
		(instances
			(project "artix-dc-scm"
				(path ""
					(reference "R194")
					(unit 1)
				)
			)
		)
	)
	(symbol
		(lib_id "antmicroCapacitors0402:C_22p_0402")
		(at 177.8 190.5 270)
		(mirror x)
		(unit 1)
		(exclude_from_sim no)
		(in_bom yes)
		(on_board yes)
		(dnp no)
		(property "Reference" "C220"
			(at 177.165 186.055 90)
			(effects
				(font
					(size 1.27 1.27)
				)
				(justify right)
			)
		)
		(property "Value" "C_22p_0402"
			(at 167.64 170.18 0)
			(effects
				(font
					(size 1.27 1.27)
					(thickness 0.15)
				)
				(justify left bottom)
				(hide yes)
			)
		)
		(property "Footprint" "antmicro-footprints:C_0402_1005Metric"
			(at 165.1 170.18 0)
			(effects
				(font
					(size 1.27 1.27)
					(thickness 0.15)
				)
				(justify left bottom)
				(hide yes)
			)
		)
		(property "Datasheet" "https://www.yageo.com/en/Chart/Download/pdf/CC0402JRNPO9BN220"
			(at 162.56 170.18 0)
			(effects
				(font
					(size 1.27 1.27)
					(thickness 0.15)
				)
				(justify left bottom)
				(hide yes)
			)
		)
		(property "Description" "SMD Multilayer Ceramic Capacitor, 22 pF, 50 V, 0402 [1005 Metric], ± 5%, C0G / NP0, CC Series"
			(at 177.8 190.5 0)
			(effects
				(font
					(size 1.27 1.27)
				)
				(hide yes)
			)
		)
		(property "Manufacturer" "YAGEO"
			(at 157.48 170.18 0)
			(effects
				(font
					(size 1.27 1.27)
					(thickness 0.15)
				)
				(justify left bottom)
				(hide yes)
			)
		)
		(property "MPN" "CC0402JRNPO9BN220"
			(at 160.02 170.18 0)
			(effects
				(font
					(size 1.27 1.27)
					(thickness 0.15)
				)
				(justify left bottom)
				(hide yes)
			)
		)
		(property "Val" "22p"
			(at 177.165 189.865 90)
			(effects
				(font
					(size 1.27 1.27)
					(thickness 0.15)
				)
				(justify right)
			)
		)
		(property "License" "Apache-2.0"
			(at 154.94 170.18 0)
			(effects
				(font
					(size 1.27 1.27)
					(thickness 0.15)
				)
				(justify left bottom)
				(hide yes)
			)
		)
		(property "Author" "Antmicro"
			(at 152.4 170.18 0)
			(effects
				(font
					(size 1.27 1.27)
					(thickness 0.15)
				)
				(justify left bottom)
				(hide yes)
			)
		)
		(property "Voltage" ""
			(at 149.86 170.18 0)
			(effects
				(font
					(size 1.27 1.27)
				)
				(justify left bottom)
				(hide yes)
			)
		)
		(property "Dielectric" ""
			(at 147.32 170.18 0)
			(effects
				(font
					(size 1.27 1.27)
				)
				(justify left bottom)
				(hide yes)
			)
		)
		(pin "1"
		)
		(pin "2"
		)
		(instances
			(project "artix-dc-scm"
				(path ""
					(reference "C220")
					(unit 1)
				)
			)
		)
	)
	(symbol
		(lib_id "antmicroResonators:Resonator_25MHz_ABM8G")
		(at 189.23 184.15 0)
		(mirror y)
		(unit 1)
		(exclude_from_sim no)
		(in_bom yes)
		(on_board yes)
		(dnp no)
		(property "Reference" "Y2"
			(at 185.42 177.8 0)
			(effects
				(font
					(size 1.27 1.27)
				)
			)
		)
		(property "Value" "Resonator_25MHz_ABM8G"
			(at 185.42 175.895 0)
			(effects
				(font
					(size 1.27 1.27)
					(thickness 0.15)
				)
				(hide yes)
			)
		)
		(property "Footprint" "antmicro-footprints:Resonator_SMD_Abracon_ABM8G_3.2x2.5mm"
			(at 166.37 194.31 0)
			(effects
				(font
					(size 1.27 1.27)
					(thickness 0.15)
				)
				(justify left bottom)
				(hide yes)
			)
		)
		(property "Datasheet" "https://abracon.com/Resonators/ABM8G.pdf"
			(at 166.37 196.85 0)
			(effects
				(font
					(size 1.27 1.27)
					(thickness 0.15)
				)
				(justify left bottom)
				(hide yes)
			)
		)
		(property "Description" "Crystal, 25 MHz, SMD, 3.2mm x 2.5mm, 30 ppm, 18 pF, 20 ppm, ABM8G"
			(at 189.23 184.15 0)
			(effects
				(font
					(size 1.27 1.27)
				)
				(hide yes)
			)
		)
		(property "MPN" "ABM8G-25.000MHZ-18-D2Y-T3"
			(at 166.37 199.39 0)
			(effects
				(font
					(size 1.27 1.27)
					(thickness 0.15)
				)
				(justify left bottom)
				(hide yes)
			)
		)
		(property "Manufacturer" "Abracon"
			(at 166.37 201.93 0)
			(effects
				(font
					(size 1.27 1.27)
					(thickness 0.15)
				)
				(justify left bottom)
				(hide yes)
			)
		)
		(property "Author" "Antmicro"
			(at 166.37 204.47 0)
			(effects
				(font
					(size 1.27 1.27)
					(thickness 0.15)
				)
				(justify left bottom)
				(hide yes)
			)
		)
		(property "License" "Apache-2.0"
			(at 166.37 207.01 0)
			(effects
				(font
					(size 1.27 1.27)
					(thickness 0.15)
				)
				(justify left bottom)
				(hide yes)
			)
		)
		(property "Val" "25 MHz"
			(at 185.42 180.34 0)
			(effects
				(font
					(size 1.27 1.27)
				)
			)
		)
		(pin "1"
		)
		(pin "2"
		)
		(pin "3"
		)
		(pin "4"
		)
		(instances
			(project "artix-dc-scm"
				(path ""
					(reference "Y2")
					(unit 1)
				)
			)
		)
	)
	(symbol
		(lib_id "antmicroModularConnectorsJacksWithMagnetics:L834-1G1T-S7")
		(at 299.72 128.27 0)
		(unit 1)
		(exclude_from_sim no)
		(in_bom yes)
		(on_board yes)
		(dnp no)
		(fields_autoplaced yes)
		(property "Reference" "J1"
			(at 308.61 120.015 0)
			(effects
				(font
					(size 1.27 1.27)
				)
			)
		)
		(property "Value" "L834-1G1T-S7"
			(at 308.61 122.555 0)
			(effects
				(font
					(size 1.27 1.27)
				)
			)
		)
		(property "Footprint" "antmicro-footprints:RJ45_BEL_L834-1G1T-S7"
			(at 332.74 135.89 0)
			(effects
				(font
					(size 1.27 1.27)
					(thickness 0.15)
				)
				(justify left bottom)
				(hide yes)
			)
		)
		(property "Datasheet" "https://www.belfuse.com/resources/drawings/magneticsolutions/dr-mag-l834-1g1t-s7.pdf"
			(at 332.74 138.43 0)
			(effects
				(font
					(size 1.27 1.27)
					(thickness 0.15)
				)
				(justify left bottom)
				(hide yes)
			)
		)
		(property "Description" "Modular connector with magnetics"
			(at 299.72 128.27 0)
			(effects
				(font
					(size 1.27 1.27)
				)
				(hide yes)
			)
		)
		(property "MPN" "L834-1G1T-S7"
			(at 332.74 140.97 0)
			(effects
				(font
					(size 1.27 1.27)
					(thickness 0.15)
				)
				(justify left bottom)
				(hide yes)
			)
		)
		(property "Manufacturer" "Bel Fuse"
			(at 332.74 143.51 0)
			(effects
				(font
					(size 1.27 1.27)
					(thickness 0.15)
				)
				(justify left bottom)
				(hide yes)
			)
		)
		(property "Author" "Antmicro"
			(at 332.74 146.05 0)
			(effects
				(font
					(size 1.27 1.27)
					(thickness 0.15)
				)
				(justify left bottom)
				(hide yes)
			)
		)
		(property "License" "Apache-2.0"
			(at 332.74 148.59 0)
			(effects
				(font
					(size 1.27 1.27)
					(thickness 0.15)
				)
				(justify left bottom)
				(hide yes)
			)
		)
		(pin "1"
		)
		(pin "10"
		)
		(pin "11"
		)
		(pin "12"
		)
		(pin "13"
		)
		(pin "14"
		)
		(pin "2"
		)
		(pin "3"
		)
		(pin "4"
		)
		(pin "5"
		)
		(pin "6"
		)
		(pin "7"
		)
		(pin "8"
		)
		(pin "9"
		)
		(pin "SH"
		)
		(pin "15"
		)
		(pin "16"
		)
		(instances
			(project "artix-dc-scm"
				(path ""
					(reference "J1")
					(unit 1)
				)
			)
		)
	)
	(symbol
		(lib_id "antmicropower:GND")
		(at 320.04 160.02 0)
		(mirror y)
		(unit 1)
		(exclude_from_sim no)
		(in_bom yes)
		(on_board yes)
		(dnp no)
		(property "Reference" "#PWR0100"
			(at 320.04 166.37 0)
			(effects
				(font
					(size 1.27 1.27)
				)
				(hide yes)
			)
		)
		(property "Value" "GND"
			(at 320.04 163.83 0)
			(effects
				(font
					(size 1.27 1.27)
				)
			)
		)
		(property "Footprint" ""
			(at 320.04 160.02 0)
			(effects
				(font
					(size 1.27 1.27)
				)
				(hide yes)
			)
		)
		(property "Datasheet" ""
			(at 320.04 160.02 0)
			(effects
				(font
					(size 1.27 1.27)
				)
				(hide yes)
			)
		)
		(property "Description" ""
			(at 320.04 160.02 0)
			(effects
				(font
					(size 1.27 1.27)
				)
				(hide yes)
			)
		)
		(property "Author" "Antmicro"
			(at 311.15 167.64 0)
			(effects
				(font
					(size 1.27 1.27)
					(thickness 0.15)
				)
				(justify left bottom)
				(hide yes)
			)
		)
		(property "License" "Apache-2.0"
			(at 311.15 170.18 0)
			(effects
				(font
					(size 1.27 1.27)
					(thickness 0.15)
				)
				(justify left bottom)
				(hide yes)
			)
		)
		(pin "1"
		)
		(instances
			(project "artix-dc-scm"
				(path ""
					(reference "#PWR0100")
					(unit 1)
				)
			)
		)
	)
	(symbol
		(lib_id "antmicroCapacitors0402:C_100n_0402")
		(at 287.02 167.64 90)
		(unit 1)
		(exclude_from_sim no)
		(in_bom yes)
		(on_board yes)
		(dnp no)
		(property "Reference" "C227"
			(at 287.655 163.195 90)
			(effects
				(font
					(size 1.27 1.27)
				)
				(justify right)
			)
		)
		(property "Value" "C_100n_0402"
			(at 297.18 147.32 0)
			(effects
				(font
					(size 1.27 1.27)
					(thickness 0.15)
				)
				(justify left bottom)
				(hide yes)
			)
		)
		(property "Footprint" "antmicro-footprints:C_0402_1005Metric"
			(at 299.72 147.32 0)
			(effects
				(font
					(size 1.27 1.27)
					(thickness 0.15)
				)
				(justify left bottom)
				(hide yes)
			)
		)
		(property "Datasheet" "https://www.murata.com/products/productdetail?partno=GRM155R61H104KE14%23"
			(at 302.26 147.32 0)
			(effects
				(font
					(size 1.27 1.27)
					(thickness 0.15)
				)
				(justify left bottom)
				(hide yes)
			)
		)
		(property "Description" "SMD Multilayer Ceramic Capacitor, 0.1 µF, 50 V, 0402 [1005 Metric], ± 10%, X5R, GRM Series"
			(at 287.02 167.64 0)
			(effects
				(font
					(size 1.27 1.27)
				)
				(hide yes)
			)
		)
		(property "Manufacturer" "Murata"
			(at 307.34 147.32 0)
			(effects
				(font
					(size 1.27 1.27)
					(thickness 0.15)
				)
				(justify left bottom)
				(hide yes)
			)
		)
		(property "MPN" "GRM155R61H104KE14D"
			(at 304.8 147.32 0)
			(effects
				(font
					(size 1.27 1.27)
					(thickness 0.15)
				)
				(justify left bottom)
				(hide yes)
			)
		)
		(property "Val" "100n"
			(at 287.655 167.005 90)
			(effects
				(font
					(size 1.27 1.27)
					(thickness 0.15)
				)
				(justify right)
			)
		)
		(property "License" "Apache-2.0"
			(at 309.88 147.32 0)
			(effects
				(font
					(size 1.27 1.27)
					(thickness 0.15)
				)
				(justify left bottom)
				(hide yes)
			)
		)
		(property "Author" "Antmicro"
			(at 312.42 147.32 0)
			(effects
				(font
					(size 1.27 1.27)
					(thickness 0.15)
				)
				(justify left bottom)
				(hide yes)
			)
		)
		(property "Voltage" "50V"
			(at 314.96 147.32 0)
			(effects
				(font
					(size 1.27 1.27)
				)
				(justify left bottom)
				(hide yes)
			)
		)
		(property "Dielectric" "X5R"
			(at 317.5 147.32 0)
			(effects
				(font
					(size 1.27 1.27)
				)
				(justify left bottom)
				(hide yes)
			)
		)
		(pin "1"
		)
		(pin "2"
		)
		(instances
			(project "artix-dc-scm"
				(path ""
					(reference "C227")
					(unit 1)
				)
			)
		)
	)
	(symbol
		(lib_id "antmicroCapacitors0402:C_100n_0402")
		(at 279.4 167.64 90)
		(unit 1)
		(exclude_from_sim no)
		(in_bom yes)
		(on_board yes)
		(dnp no)
		(property "Reference" "C226"
			(at 280.035 163.195 90)
			(effects
				(font
					(size 1.27 1.27)
				)
				(justify right)
			)
		)
		(property "Value" "C_100n_0402"
			(at 289.56 147.32 0)
			(effects
				(font
					(size 1.27 1.27)
					(thickness 0.15)
				)
				(justify left bottom)
				(hide yes)
			)
		)
		(property "Footprint" "antmicro-footprints:C_0402_1005Metric"
			(at 292.1 147.32 0)
			(effects
				(font
					(size 1.27 1.27)
					(thickness 0.15)
				)
				(justify left bottom)
				(hide yes)
			)
		)
		(property "Datasheet" "https://www.murata.com/products/productdetail?partno=GRM155R61H104KE14%23"
			(at 294.64 147.32 0)
			(effects
				(font
					(size 1.27 1.27)
					(thickness 0.15)
				)
				(justify left bottom)
				(hide yes)
			)
		)
		(property "Description" "SMD Multilayer Ceramic Capacitor, 0.1 µF, 50 V, 0402 [1005 Metric], ± 10%, X5R, GRM Series"
			(at 279.4 167.64 0)
			(effects
				(font
					(size 1.27 1.27)
				)
				(hide yes)
			)
		)
		(property "Manufacturer" "Murata"
			(at 299.72 147.32 0)
			(effects
				(font
					(size 1.27 1.27)
					(thickness 0.15)
				)
				(justify left bottom)
				(hide yes)
			)
		)
		(property "MPN" "GRM155R61H104KE14D"
			(at 297.18 147.32 0)
			(effects
				(font
					(size 1.27 1.27)
					(thickness 0.15)
				)
				(justify left bottom)
				(hide yes)
			)
		)
		(property "Val" "100n"
			(at 280.035 167.005 90)
			(effects
				(font
					(size 1.27 1.27)
					(thickness 0.15)
				)
				(justify right)
			)
		)
		(property "License" "Apache-2.0"
			(at 302.26 147.32 0)
			(effects
				(font
					(size 1.27 1.27)
					(thickness 0.15)
				)
				(justify left bottom)
				(hide yes)
			)
		)
		(property "Author" "Antmicro"
			(at 304.8 147.32 0)
			(effects
				(font
					(size 1.27 1.27)
					(thickness 0.15)
				)
				(justify left bottom)
				(hide yes)
			)
		)
		(property "Voltage" "50V"
			(at 307.34 147.32 0)
			(effects
				(font
					(size 1.27 1.27)
				)
				(justify left bottom)
				(hide yes)
			)
		)
		(property "Dielectric" "X5R"
			(at 309.88 147.32 0)
			(effects
				(font
					(size 1.27 1.27)
				)
				(justify left bottom)
				(hide yes)
			)
		)
		(pin "1"
		)
		(pin "2"
		)
		(instances
			(project "artix-dc-scm"
				(path ""
					(reference "C226")
					(unit 1)
				)
			)
		)
	)
	(symbol
		(lib_id "antmicroCapacitors0402:C_100n_0402")
		(at 270.51 167.64 90)
		(unit 1)
		(exclude_from_sim no)
		(in_bom yes)
		(on_board yes)
		(dnp no)
		(property "Reference" "C225"
			(at 271.145 163.195 90)
			(effects
				(font
					(size 1.27 1.27)
				)
				(justify right)
			)
		)
		(property "Value" "C_100n_0402"
			(at 280.67 147.32 0)
			(effects
				(font
					(size 1.27 1.27)
					(thickness 0.15)
				)
				(justify left bottom)
				(hide yes)
			)
		)
		(property "Footprint" "antmicro-footprints:C_0402_1005Metric"
			(at 283.21 147.32 0)
			(effects
				(font
					(size 1.27 1.27)
					(thickness 0.15)
				)
				(justify left bottom)
				(hide yes)
			)
		)
		(property "Datasheet" "https://www.murata.com/products/productdetail?partno=GRM155R61H104KE14%23"
			(at 285.75 147.32 0)
			(effects
				(font
					(size 1.27 1.27)
					(thickness 0.15)
				)
				(justify left bottom)
				(hide yes)
			)
		)
		(property "Description" "SMD Multilayer Ceramic Capacitor, 0.1 µF, 50 V, 0402 [1005 Metric], ± 10%, X5R, GRM Series"
			(at 270.51 167.64 0)
			(effects
				(font
					(size 1.27 1.27)
				)
				(hide yes)
			)
		)
		(property "Manufacturer" "Murata"
			(at 290.83 147.32 0)
			(effects
				(font
					(size 1.27 1.27)
					(thickness 0.15)
				)
				(justify left bottom)
				(hide yes)
			)
		)
		(property "MPN" "GRM155R61H104KE14D"
			(at 288.29 147.32 0)
			(effects
				(font
					(size 1.27 1.27)
					(thickness 0.15)
				)
				(justify left bottom)
				(hide yes)
			)
		)
		(property "Val" "100n"
			(at 271.145 167.005 90)
			(effects
				(font
					(size 1.27 1.27)
					(thickness 0.15)
				)
				(justify right)
			)
		)
		(property "License" "Apache-2.0"
			(at 293.37 147.32 0)
			(effects
				(font
					(size 1.27 1.27)
					(thickness 0.15)
				)
				(justify left bottom)
				(hide yes)
			)
		)
		(property "Author" "Antmicro"
			(at 295.91 147.32 0)
			(effects
				(font
					(size 1.27 1.27)
					(thickness 0.15)
				)
				(justify left bottom)
				(hide yes)
			)
		)
		(property "Voltage" "50V"
			(at 298.45 147.32 0)
			(effects
				(font
					(size 1.27 1.27)
				)
				(justify left bottom)
				(hide yes)
			)
		)
		(property "Dielectric" "X5R"
			(at 300.99 147.32 0)
			(effects
				(font
					(size 1.27 1.27)
				)
				(justify left bottom)
				(hide yes)
			)
		)
		(pin "1"
		)
		(pin "2"
		)
		(instances
			(project "artix-dc-scm"
				(path ""
					(reference "C225")
					(unit 1)
				)
			)
		)
	)
	(symbol
		(lib_id "antmicroCapacitors0402:C_100n_0402")
		(at 295.91 167.64 90)
		(unit 1)
		(exclude_from_sim no)
		(in_bom yes)
		(on_board yes)
		(dnp no)
		(property "Reference" "C228"
			(at 296.545 163.195 90)
			(effects
				(font
					(size 1.27 1.27)
				)
				(justify right)
			)
		)
		(property "Value" "C_100n_0402"
			(at 306.07 147.32 0)
			(effects
				(font
					(size 1.27 1.27)
					(thickness 0.15)
				)
				(justify left bottom)
				(hide yes)
			)
		)
		(property "Footprint" "antmicro-footprints:C_0402_1005Metric"
			(at 308.61 147.32 0)
			(effects
				(font
					(size 1.27 1.27)
					(thickness 0.15)
				)
				(justify left bottom)
				(hide yes)
			)
		)
		(property "Datasheet" "https://www.murata.com/products/productdetail?partno=GRM155R61H104KE14%23"
			(at 311.15 147.32 0)
			(effects
				(font
					(size 1.27 1.27)
					(thickness 0.15)
				)
				(justify left bottom)
				(hide yes)
			)
		)
		(property "Description" "SMD Multilayer Ceramic Capacitor, 0.1 µF, 50 V, 0402 [1005 Metric], ± 10%, X5R, GRM Series"
			(at 295.91 167.64 0)
			(effects
				(font
					(size 1.27 1.27)
				)
				(hide yes)
			)
		)
		(property "Manufacturer" "Murata"
			(at 316.23 147.32 0)
			(effects
				(font
					(size 1.27 1.27)
					(thickness 0.15)
				)
				(justify left bottom)
				(hide yes)
			)
		)
		(property "MPN" "GRM155R61H104KE14D"
			(at 313.69 147.32 0)
			(effects
				(font
					(size 1.27 1.27)
					(thickness 0.15)
				)
				(justify left bottom)
				(hide yes)
			)
		)
		(property "Val" "100n"
			(at 296.545 167.005 90)
			(effects
				(font
					(size 1.27 1.27)
					(thickness 0.15)
				)
				(justify right)
			)
		)
		(property "License" "Apache-2.0"
			(at 318.77 147.32 0)
			(effects
				(font
					(size 1.27 1.27)
					(thickness 0.15)
				)
				(justify left bottom)
				(hide yes)
			)
		)
		(property "Author" "Antmicro"
			(at 321.31 147.32 0)
			(effects
				(font
					(size 1.27 1.27)
					(thickness 0.15)
				)
				(justify left bottom)
				(hide yes)
			)
		)
		(property "Voltage" "50V"
			(at 323.85 147.32 0)
			(effects
				(font
					(size 1.27 1.27)
				)
				(justify left bottom)
				(hide yes)
			)
		)
		(property "Dielectric" "X5R"
			(at 326.39 147.32 0)
			(effects
				(font
					(size 1.27 1.27)
				)
				(justify left bottom)
				(hide yes)
			)
		)
		(pin "1"
		)
		(pin "2"
		)
		(instances
			(project "artix-dc-scm"
				(path ""
					(reference "C228")
					(unit 1)
				)
			)
		)
	)
	(symbol
		(lib_id "antmicropower:GND")
		(at 290.83 113.03 0)
		(unit 1)
		(exclude_from_sim no)
		(in_bom yes)
		(on_board yes)
		(dnp no)
		(property "Reference" "#PWR0165"
			(at 290.83 119.38 0)
			(effects
				(font
					(size 1.27 1.27)
				)
				(hide yes)
			)
		)
		(property "Value" "GND"
			(at 290.83 116.84 0)
			(effects
				(font
					(size 1.27 1.27)
				)
			)
		)
		(property "Footprint" ""
			(at 290.83 113.03 0)
			(effects
				(font
					(size 1.27 1.27)
				)
				(hide yes)
			)
		)
		(property "Datasheet" ""
			(at 290.83 113.03 0)
			(effects
				(font
					(size 1.27 1.27)
				)
				(hide yes)
			)
		)
		(property "Description" ""
			(at 290.83 113.03 0)
			(effects
				(font
					(size 1.27 1.27)
				)
				(hide yes)
			)
		)
		(property "Author" "Antmicro"
			(at 299.72 120.65 0)
			(effects
				(font
					(size 1.27 1.27)
					(thickness 0.15)
				)
				(justify left bottom)
				(hide yes)
			)
		)
		(property "License" "Apache-2.0"
			(at 299.72 123.19 0)
			(effects
				(font
					(size 1.27 1.27)
					(thickness 0.15)
				)
				(justify left bottom)
				(hide yes)
			)
		)
		(pin "1"
		)
		(instances
			(project "artix-dc-scm"
				(path ""
					(reference "#PWR0165")
					(unit 1)
				)
			)
		)
	)
	(symbol
		(lib_id "antmicropower:GND")
		(at 177.8 92.71 0)
		(unit 1)
		(exclude_from_sim no)
		(in_bom yes)
		(on_board yes)
		(dnp no)
		(property "Reference" "#PWR0130"
			(at 177.8 99.06 0)
			(effects
				(font
					(size 1.27 1.27)
				)
				(hide yes)
			)
		)
		(property "Value" "GND"
			(at 177.8 96.52 0)
			(effects
				(font
					(size 1.27 1.27)
				)
			)
		)
		(property "Footprint" ""
			(at 177.8 92.71 0)
			(effects
				(font
					(size 1.27 1.27)
				)
				(hide yes)
			)
		)
		(property "Datasheet" ""
			(at 177.8 92.71 0)
			(effects
				(font
					(size 1.27 1.27)
				)
				(hide yes)
			)
		)
		(property "Description" ""
			(at 177.8 92.71 0)
			(effects
				(font
					(size 1.27 1.27)
				)
				(hide yes)
			)
		)
		(property "Author" "Antmicro"
			(at 186.69 100.33 0)
			(effects
				(font
					(size 1.27 1.27)
					(thickness 0.15)
				)
				(justify left bottom)
				(hide yes)
			)
		)
		(property "License" "Apache-2.0"
			(at 186.69 102.87 0)
			(effects
				(font
					(size 1.27 1.27)
					(thickness 0.15)
				)
				(justify left bottom)
				(hide yes)
			)
		)
		(pin "1"
		)
		(instances
			(project "artix-dc-scm"
				(path ""
					(reference "#PWR0130")
					(unit 1)
				)
			)
		)
	)
	(symbol
		(lib_id "antmicropower:PWR_FLAG")
		(at 177.8 110.49 270)
		(unit 1)
		(exclude_from_sim no)
		(in_bom yes)
		(on_board yes)
		(dnp no)
		(property "Reference" "#FLG0105"
			(at 179.705 110.49 0)
			(effects
				(font
					(size 1.27 1.27)
				)
				(hide yes)
			)
		)
		(property "Value" "PWR_FLAG"
			(at 181.61 110.49 0)
			(effects
				(font
					(size 1.27 1.27)
				)
			)
		)
		(property "Footprint" ""
			(at 177.8 110.49 0)
			(effects
				(font
					(size 1.27 1.27)
				)
				(hide yes)
			)
		)
		(property "Datasheet" ""
			(at 177.8 110.49 0)
			(effects
				(font
					(size 1.27 1.27)
				)
				(hide yes)
			)
		)
		(property "Description" ""
			(at 177.8 110.49 0)
			(effects
				(font
					(size 1.27 1.27)
				)
				(hide yes)
			)
		)
		(pin "1"
		)
		(instances
			(project "artix-dc-scm"
				(path ""
					(reference "#FLG0105")
					(unit 1)
				)
			)
		)
	)
	(symbol
		(lib_id "antmicropower:GND")
		(at 290.83 73.66 0)
		(unit 1)
		(exclude_from_sim no)
		(in_bom yes)
		(on_board yes)
		(dnp no)
		(property "Reference" "#PWR0173"
			(at 290.83 80.01 0)
			(effects
				(font
					(size 1.27 1.27)
				)
				(hide yes)
			)
		)
		(property "Value" "GND"
			(at 290.83 77.47 0)
			(effects
				(font
					(size 1.27 1.27)
				)
			)
		)
		(property "Footprint" ""
			(at 290.83 73.66 0)
			(effects
				(font
					(size 1.27 1.27)
				)
				(hide yes)
			)
		)
		(property "Datasheet" ""
			(at 290.83 73.66 0)
			(effects
				(font
					(size 1.27 1.27)
				)
				(hide yes)
			)
		)
		(property "Description" ""
			(at 290.83 73.66 0)
			(effects
				(font
					(size 1.27 1.27)
				)
				(hide yes)
			)
		)
		(property "Author" "Antmicro"
			(at 299.72 81.28 0)
			(effects
				(font
					(size 1.27 1.27)
					(thickness 0.15)
				)
				(justify left bottom)
				(hide yes)
			)
		)
		(property "License" "Apache-2.0"
			(at 299.72 83.82 0)
			(effects
				(font
					(size 1.27 1.27)
					(thickness 0.15)
				)
				(justify left bottom)
				(hide yes)
			)
		)
		(pin "1"
		)
		(instances
			(project "artix-dc-scm"
				(path ""
					(reference "#PWR0173")
					(unit 1)
				)
			)
		)
	)
	(symbol
		(lib_id "antmicropower:PWR_FLAG")
		(at 266.7 120.65 270)
		(unit 1)
		(exclude_from_sim no)
		(in_bom yes)
		(on_board yes)
		(dnp no)
		(fields_autoplaced yes)
		(property "Reference" "#FLG0101"
			(at 268.605 120.65 0)
			(effects
				(font
					(size 1.27 1.27)
				)
				(hide yes)
			)
		)
		(property "Value" "PWR_FLAG"
			(at 269.875 120.6499 90)
			(effects
				(font
					(size 1.27 1.27)
				)
				(justify left)
			)
		)
		(property "Footprint" ""
			(at 266.7 120.65 0)
			(effects
				(font
					(size 1.27 1.27)
				)
				(hide yes)
			)
		)
		(property "Datasheet" ""
			(at 266.7 120.65 0)
			(effects
				(font
					(size 1.27 1.27)
				)
				(hide yes)
			)
		)
		(property "Description" ""
			(at 266.7 120.65 0)
			(effects
				(font
					(size 1.27 1.27)
				)
				(hide yes)
			)
		)
		(pin "1"
		)
		(instances
			(project "artix-dc-scm"
				(path ""
					(reference "#FLG0101")
					(unit 1)
				)
			)
		)
	)
	(symbol
		(lib_id "antmicropower:GND")
		(at 161.29 92.71 0)
		(unit 1)
		(exclude_from_sim no)
		(in_bom yes)
		(on_board yes)
		(dnp no)
		(property "Reference" "#PWR0117"
			(at 161.29 99.06 0)
			(effects
				(font
					(size 1.27 1.27)
				)
				(hide yes)
			)
		)
		(property "Value" "GND"
			(at 161.29 96.52 0)
			(effects
				(font
					(size 1.27 1.27)
				)
			)
		)
		(property "Footprint" ""
			(at 161.29 92.71 0)
			(effects
				(font
					(size 1.27 1.27)
				)
				(hide yes)
			)
		)
		(property "Datasheet" ""
			(at 161.29 92.71 0)
			(effects
				(font
					(size 1.27 1.27)
				)
				(hide yes)
			)
		)
		(property "Description" ""
			(at 161.29 92.71 0)
			(effects
				(font
					(size 1.27 1.27)
				)
				(hide yes)
			)
		)
		(property "Author" "Antmicro"
			(at 170.18 100.33 0)
			(effects
				(font
					(size 1.27 1.27)
					(thickness 0.15)
				)
				(justify left bottom)
				(hide yes)
			)
		)
		(property "License" "Apache-2.0"
			(at 170.18 102.87 0)
			(effects
				(font
					(size 1.27 1.27)
					(thickness 0.15)
				)
				(justify left bottom)
				(hide yes)
			)
		)
		(pin "1"
		)
		(instances
			(project "artix-dc-scm"
				(path ""
					(reference "#PWR0117")
					(unit 1)
				)
			)
		)
	)
	(symbol
		(lib_id "antmicropower:GND")
		(at 279.4 167.64 0)
		(unit 1)
		(exclude_from_sim no)
		(in_bom yes)
		(on_board yes)
		(dnp no)
		(property "Reference" "#PWR0181"
			(at 279.4 173.99 0)
			(effects
				(font
					(size 1.27 1.27)
				)
				(hide yes)
			)
		)
		(property "Value" "GND"
			(at 279.4 171.45 0)
			(effects
				(font
					(size 1.27 1.27)
				)
			)
		)
		(property "Footprint" ""
			(at 279.4 167.64 0)
			(effects
				(font
					(size 1.27 1.27)
				)
				(hide yes)
			)
		)
		(property "Datasheet" ""
			(at 279.4 167.64 0)
			(effects
				(font
					(size 1.27 1.27)
				)
				(hide yes)
			)
		)
		(property "Description" ""
			(at 279.4 167.64 0)
			(effects
				(font
					(size 1.27 1.27)
				)
				(hide yes)
			)
		)
		(property "Author" "Antmicro"
			(at 288.29 175.26 0)
			(effects
				(font
					(size 1.27 1.27)
					(thickness 0.15)
				)
				(justify left bottom)
				(hide yes)
			)
		)
		(property "License" "Apache-2.0"
			(at 288.29 177.8 0)
			(effects
				(font
					(size 1.27 1.27)
					(thickness 0.15)
				)
				(justify left bottom)
				(hide yes)
			)
		)
		(pin "1"
		)
		(instances
			(project "artix-dc-scm"
				(path ""
					(reference "#PWR0181")
					(unit 1)
				)
			)
		)
	)
	(symbol
		(lib_id "antmicropower:GND")
		(at 191.77 190.5 0)
		(mirror y)
		(unit 1)
		(exclude_from_sim no)
		(in_bom yes)
		(on_board yes)
		(dnp no)
		(property "Reference" "#PWR0113"
			(at 191.77 196.85 0)
			(effects
				(font
					(size 1.27 1.27)
				)
				(hide yes)
			)
		)
		(property "Value" "GND"
			(at 191.77 194.31 0)
			(effects
				(font
					(size 1.27 1.27)
				)
			)
		)
		(property "Footprint" ""
			(at 191.77 190.5 0)
			(effects
				(font
					(size 1.27 1.27)
				)
				(hide yes)
			)
		)
		(property "Datasheet" ""
			(at 191.77 190.5 0)
			(effects
				(font
					(size 1.27 1.27)
				)
				(hide yes)
			)
		)
		(property "Description" ""
			(at 191.77 190.5 0)
			(effects
				(font
					(size 1.27 1.27)
				)
				(hide yes)
			)
		)
		(property "Author" "Antmicro"
			(at 182.88 198.12 0)
			(effects
				(font
					(size 1.27 1.27)
					(thickness 0.15)
				)
				(justify left bottom)
				(hide yes)
			)
		)
		(property "License" "Apache-2.0"
			(at 182.88 200.66 0)
			(effects
				(font
					(size 1.27 1.27)
					(thickness 0.15)
				)
				(justify left bottom)
				(hide yes)
			)
		)
		(pin "1"
		)
		(instances
			(project "artix-dc-scm"
				(path ""
					(reference "#PWR0113")
					(unit 1)
				)
			)
		)
	)
	(symbol
		(lib_id "antmicropower:PWR_FLAG")
		(at 243.84 176.53 270)
		(unit 1)
		(exclude_from_sim no)
		(in_bom yes)
		(on_board yes)
		(dnp no)
		(fields_autoplaced yes)
		(property "Reference" "#FLG01"
			(at 245.745 176.53 0)
			(effects
				(font
					(size 1.27 1.27)
				)
				(hide yes)
			)
		)
		(property "Value" "PWR_FLAG"
			(at 247.015 176.5299 90)
			(effects
				(font
					(size 1.27 1.27)
				)
				(justify left)
			)
		)
		(property "Footprint" ""
			(at 243.84 176.53 0)
			(effects
				(font
					(size 1.27 1.27)
				)
				(hide yes)
			)
		)
		(property "Datasheet" ""
			(at 243.84 176.53 0)
			(effects
				(font
					(size 1.27 1.27)
				)
				(hide yes)
			)
		)
		(property "Description" ""
			(at 243.84 176.53 0)
			(effects
				(font
					(size 1.27 1.27)
				)
				(hide yes)
			)
		)
		(pin "1"
		)
		(instances
			(project "artix-dc-scm"
				(path ""
					(reference "#FLG01")
					(unit 1)
				)
			)
		)
	)
	(symbol
		(lib_id "antmicropower:GND")
		(at 168.91 113.03 0)
		(unit 1)
		(exclude_from_sim no)
		(in_bom yes)
		(on_board yes)
		(dnp no)
		(property "Reference" "#PWR0140"
			(at 168.91 119.38 0)
			(effects
				(font
					(size 1.27 1.27)
				)
				(hide yes)
			)
		)
		(property "Value" "GND"
			(at 168.91 116.84 0)
			(effects
				(font
					(size 1.27 1.27)
				)
			)
		)
		(property "Footprint" ""
			(at 168.91 113.03 0)
			(effects
				(font
					(size 1.27 1.27)
				)
				(hide yes)
			)
		)
		(property "Datasheet" ""
			(at 168.91 113.03 0)
			(effects
				(font
					(size 1.27 1.27)
				)
				(hide yes)
			)
		)
		(property "Description" ""
			(at 168.91 113.03 0)
			(effects
				(font
					(size 1.27 1.27)
				)
				(hide yes)
			)
		)
		(property "Author" "Antmicro"
			(at 177.8 120.65 0)
			(effects
				(font
					(size 1.27 1.27)
					(thickness 0.15)
				)
				(justify left bottom)
				(hide yes)
			)
		)
		(property "License" "Apache-2.0"
			(at 177.8 123.19 0)
			(effects
				(font
					(size 1.27 1.27)
					(thickness 0.15)
				)
				(justify left bottom)
				(hide yes)
			)
		)
		(pin "1"
		)
		(instances
			(project "artix-dc-scm"
				(path ""
					(reference "#PWR0140")
					(unit 1)
				)
			)
		)
	)
	(symbol
		(lib_id "antmicropower:GND")
		(at 316.23 73.66 0)
		(unit 1)
		(exclude_from_sim no)
		(in_bom yes)
		(on_board yes)
		(dnp no)
		(property "Reference" "#PWR0178"
			(at 316.23 80.01 0)
			(effects
				(font
					(size 1.27 1.27)
				)
				(hide yes)
			)
		)
		(property "Value" "GND"
			(at 316.23 77.47 0)
			(effects
				(font
					(size 1.27 1.27)
				)
			)
		)
		(property "Footprint" ""
			(at 316.23 73.66 0)
			(effects
				(font
					(size 1.27 1.27)
				)
				(hide yes)
			)
		)
		(property "Datasheet" ""
			(at 316.23 73.66 0)
			(effects
				(font
					(size 1.27 1.27)
				)
				(hide yes)
			)
		)
		(property "Description" ""
			(at 316.23 73.66 0)
			(effects
				(font
					(size 1.27 1.27)
				)
				(hide yes)
			)
		)
		(property "Author" "Antmicro"
			(at 325.12 81.28 0)
			(effects
				(font
					(size 1.27 1.27)
					(thickness 0.15)
				)
				(justify left bottom)
				(hide yes)
			)
		)
		(property "License" "Apache-2.0"
			(at 325.12 83.82 0)
			(effects
				(font
					(size 1.27 1.27)
					(thickness 0.15)
				)
				(justify left bottom)
				(hide yes)
			)
		)
		(pin "1"
		)
		(instances
			(project "artix-dc-scm"
				(path ""
					(reference "#PWR0178")
					(unit 1)
				)
			)
		)
	)
	(symbol
		(lib_id "antmicropower:GND")
		(at 274.32 113.03 0)
		(unit 1)
		(exclude_from_sim no)
		(in_bom yes)
		(on_board yes)
		(dnp no)
		(property "Reference" "#PWR0151"
			(at 274.32 119.38 0)
			(effects
				(font
					(size 1.27 1.27)
				)
				(hide yes)
			)
		)
		(property "Value" "GND"
			(at 274.32 116.84 0)
			(effects
				(font
					(size 1.27 1.27)
				)
			)
		)
		(property "Footprint" ""
			(at 274.32 113.03 0)
			(effects
				(font
					(size 1.27 1.27)
				)
				(hide yes)
			)
		)
		(property "Datasheet" ""
			(at 274.32 113.03 0)
			(effects
				(font
					(size 1.27 1.27)
				)
				(hide yes)
			)
		)
		(property "Description" ""
			(at 274.32 113.03 0)
			(effects
				(font
					(size 1.27 1.27)
				)
				(hide yes)
			)
		)
		(property "Author" "Antmicro"
			(at 283.21 120.65 0)
			(effects
				(font
					(size 1.27 1.27)
					(thickness 0.15)
				)
				(justify left bottom)
				(hide yes)
			)
		)
		(property "License" "Apache-2.0"
			(at 283.21 123.19 0)
			(effects
				(font
					(size 1.27 1.27)
					(thickness 0.15)
				)
				(justify left bottom)
				(hide yes)
			)
		)
		(pin "1"
		)
		(instances
			(project "artix-dc-scm"
				(path ""
					(reference "#PWR0151")
					(unit 1)
				)
			)
		)
	)
	(symbol
		(lib_id "antmicropower:GND")
		(at 257.81 73.66 0)
		(unit 1)
		(exclude_from_sim no)
		(in_bom yes)
		(on_board yes)
		(dnp no)
		(property "Reference" "#PWR0167"
			(at 257.81 80.01 0)
			(effects
				(font
					(size 1.27 1.27)
				)
				(hide yes)
			)
		)
		(property "Value" "GND"
			(at 257.81 77.47 0)
			(effects
				(font
					(size 1.27 1.27)
				)
			)
		)
		(property "Footprint" ""
			(at 257.81 73.66 0)
			(effects
				(font
					(size 1.27 1.27)
				)
				(hide yes)
			)
		)
		(property "Datasheet" ""
			(at 257.81 73.66 0)
			(effects
				(font
					(size 1.27 1.27)
				)
				(hide yes)
			)
		)
		(property "Description" ""
			(at 257.81 73.66 0)
			(effects
				(font
					(size 1.27 1.27)
				)
				(hide yes)
			)
		)
		(property "Author" "Antmicro"
			(at 266.7 81.28 0)
			(effects
				(font
					(size 1.27 1.27)
					(thickness 0.15)
				)
				(justify left bottom)
				(hide yes)
			)
		)
		(property "License" "Apache-2.0"
			(at 266.7 83.82 0)
			(effects
				(font
					(size 1.27 1.27)
					(thickness 0.15)
				)
				(justify left bottom)
				(hide yes)
			)
		)
		(pin "1"
		)
		(instances
			(project "artix-dc-scm"
				(path ""
					(reference "#PWR0167")
					(unit 1)
				)
			)
		)
	)
	(symbol
		(lib_id "antmicropower:GND")
		(at 287.02 167.64 0)
		(unit 1)
		(exclude_from_sim no)
		(in_bom yes)
		(on_board yes)
		(dnp no)
		(property "Reference" "#PWR0183"
			(at 287.02 173.99 0)
			(effects
				(font
					(size 1.27 1.27)
				)
				(hide yes)
			)
		)
		(property "Value" "GND"
			(at 287.02 171.45 0)
			(effects
				(font
					(size 1.27 1.27)
				)
			)
		)
		(property "Footprint" ""
			(at 287.02 167.64 0)
			(effects
				(font
					(size 1.27 1.27)
				)
				(hide yes)
			)
		)
		(property "Datasheet" ""
			(at 287.02 167.64 0)
			(effects
				(font
					(size 1.27 1.27)
				)
				(hide yes)
			)
		)
		(property "Description" ""
			(at 287.02 167.64 0)
			(effects
				(font
					(size 1.27 1.27)
				)
				(hide yes)
			)
		)
		(property "Author" "Antmicro"
			(at 295.91 175.26 0)
			(effects
				(font
					(size 1.27 1.27)
					(thickness 0.15)
				)
				(justify left bottom)
				(hide yes)
			)
		)
		(property "License" "Apache-2.0"
			(at 295.91 177.8 0)
			(effects
				(font
					(size 1.27 1.27)
					(thickness 0.15)
				)
				(justify left bottom)
				(hide yes)
			)
		)
		(pin "1"
		)
		(instances
			(project "artix-dc-scm"
				(path ""
					(reference "#PWR0183")
					(unit 1)
				)
			)
		)
	)
	(symbol
		(lib_id "antmicropower:GND")
		(at 283.21 113.03 0)
		(unit 1)
		(exclude_from_sim no)
		(in_bom yes)
		(on_board yes)
		(dnp no)
		(property "Reference" "#PWR0166"
			(at 283.21 119.38 0)
			(effects
				(font
					(size 1.27 1.27)
				)
				(hide yes)
			)
		)
		(property "Value" "GND"
			(at 283.21 116.84 0)
			(effects
				(font
					(size 1.27 1.27)
				)
			)
		)
		(property "Footprint" ""
			(at 283.21 113.03 0)
			(effects
				(font
					(size 1.27 1.27)
				)
				(hide yes)
			)
		)
		(property "Datasheet" ""
			(at 283.21 113.03 0)
			(effects
				(font
					(size 1.27 1.27)
				)
				(hide yes)
			)
		)
		(property "Description" ""
			(at 283.21 113.03 0)
			(effects
				(font
					(size 1.27 1.27)
				)
				(hide yes)
			)
		)
		(property "Author" "Antmicro"
			(at 292.1 120.65 0)
			(effects
				(font
					(size 1.27 1.27)
					(thickness 0.15)
				)
				(justify left bottom)
				(hide yes)
			)
		)
		(property "License" "Apache-2.0"
			(at 292.1 123.19 0)
			(effects
				(font
					(size 1.27 1.27)
					(thickness 0.15)
				)
				(justify left bottom)
				(hide yes)
			)
		)
		(pin "1"
		)
		(instances
			(project "artix-dc-scm"
				(path ""
					(reference "#PWR0166")
					(unit 1)
				)
			)
		)
	)
	(symbol
		(lib_id "antmicropower:GND")
		(at 266.7 92.71 0)
		(unit 1)
		(exclude_from_sim no)
		(in_bom yes)
		(on_board yes)
		(dnp no)
		(property "Reference" "#PWR0156"
			(at 266.7 99.06 0)
			(effects
				(font
					(size 1.27 1.27)
				)
				(hide yes)
			)
		)
		(property "Value" "GND"
			(at 266.7 96.52 0)
			(effects
				(font
					(size 1.27 1.27)
				)
			)
		)
		(property "Footprint" ""
			(at 266.7 92.71 0)
			(effects
				(font
					(size 1.27 1.27)
				)
				(hide yes)
			)
		)
		(property "Datasheet" ""
			(at 266.7 92.71 0)
			(effects
				(font
					(size 1.27 1.27)
				)
				(hide yes)
			)
		)
		(property "Description" ""
			(at 266.7 92.71 0)
			(effects
				(font
					(size 1.27 1.27)
				)
				(hide yes)
			)
		)
		(property "Author" "Antmicro"
			(at 275.59 100.33 0)
			(effects
				(font
					(size 1.27 1.27)
					(thickness 0.15)
				)
				(justify left bottom)
				(hide yes)
			)
		)
		(property "License" "Apache-2.0"
			(at 275.59 102.87 0)
			(effects
				(font
					(size 1.27 1.27)
					(thickness 0.15)
				)
				(justify left bottom)
				(hide yes)
			)
		)
		(pin "1"
		)
		(instances
			(project "artix-dc-scm"
				(path ""
					(reference "#PWR0156")
					(unit 1)
				)
			)
		)
	)
	(symbol
		(lib_id "antmicropower:GND")
		(at 283.21 73.66 0)
		(unit 1)
		(exclude_from_sim no)
		(in_bom yes)
		(on_board yes)
		(dnp no)
		(property "Reference" "#PWR0174"
			(at 283.21 80.01 0)
			(effects
				(font
					(size 1.27 1.27)
				)
				(hide yes)
			)
		)
		(property "Value" "GND"
			(at 283.21 77.47 0)
			(effects
				(font
					(size 1.27 1.27)
				)
			)
		)
		(property "Footprint" ""
			(at 283.21 73.66 0)
			(effects
				(font
					(size 1.27 1.27)
				)
				(hide yes)
			)
		)
		(property "Datasheet" ""
			(at 283.21 73.66 0)
			(effects
				(font
					(size 1.27 1.27)
				)
				(hide yes)
			)
		)
		(property "Description" ""
			(at 283.21 73.66 0)
			(effects
				(font
					(size 1.27 1.27)
				)
				(hide yes)
			)
		)
		(property "Author" "Antmicro"
			(at 292.1 81.28 0)
			(effects
				(font
					(size 1.27 1.27)
					(thickness 0.15)
				)
				(justify left bottom)
				(hide yes)
			)
		)
		(property "License" "Apache-2.0"
			(at 292.1 83.82 0)
			(effects
				(font
					(size 1.27 1.27)
					(thickness 0.15)
				)
				(justify left bottom)
				(hide yes)
			)
		)
		(pin "1"
		)
		(instances
			(project "artix-dc-scm"
				(path ""
					(reference "#PWR0174")
					(unit 1)
				)
			)
		)
	)
	(symbol
		(lib_id "antmicropower:GND")
		(at 185.42 190.5 0)
		(mirror y)
		(unit 1)
		(exclude_from_sim no)
		(in_bom yes)
		(on_board yes)
		(dnp no)
		(property "Reference" "#PWR0111"
			(at 185.42 196.85 0)
			(effects
				(font
					(size 1.27 1.27)
				)
				(hide yes)
			)
		)
		(property "Value" "GND"
			(at 185.42 194.31 0)
			(effects
				(font
					(size 1.27 1.27)
				)
			)
		)
		(property "Footprint" ""
			(at 185.42 190.5 0)
			(effects
				(font
					(size 1.27 1.27)
				)
				(hide yes)
			)
		)
		(property "Datasheet" ""
			(at 185.42 190.5 0)
			(effects
				(font
					(size 1.27 1.27)
				)
				(hide yes)
			)
		)
		(property "Description" ""
			(at 185.42 190.5 0)
			(effects
				(font
					(size 1.27 1.27)
				)
				(hide yes)
			)
		)
		(property "Author" "Antmicro"
			(at 176.53 198.12 0)
			(effects
				(font
					(size 1.27 1.27)
					(thickness 0.15)
				)
				(justify left bottom)
				(hide yes)
			)
		)
		(property "License" "Apache-2.0"
			(at 176.53 200.66 0)
			(effects
				(font
					(size 1.27 1.27)
					(thickness 0.15)
				)
				(justify left bottom)
				(hide yes)
			)
		)
		(pin "1"
		)
		(instances
			(project "artix-dc-scm"
				(path ""
					(reference "#PWR0111")
					(unit 1)
				)
			)
		)
	)
	(symbol
		(lib_id "antmicropower:GND")
		(at 177.8 190.5 0)
		(mirror y)
		(unit 1)
		(exclude_from_sim no)
		(in_bom yes)
		(on_board yes)
		(dnp no)
		(property "Reference" "#PWR0115"
			(at 177.8 196.85 0)
			(effects
				(font
					(size 1.27 1.27)
				)
				(hide yes)
			)
		)
		(property "Value" "GND"
			(at 177.8 194.31 0)
			(effects
				(font
					(size 1.27 1.27)
				)
			)
		)
		(property "Footprint" ""
			(at 177.8 190.5 0)
			(effects
				(font
					(size 1.27 1.27)
				)
				(hide yes)
			)
		)
		(property "Datasheet" ""
			(at 177.8 190.5 0)
			(effects
				(font
					(size 1.27 1.27)
				)
				(hide yes)
			)
		)
		(property "Description" ""
			(at 177.8 190.5 0)
			(effects
				(font
					(size 1.27 1.27)
				)
				(hide yes)
			)
		)
		(property "Author" "Antmicro"
			(at 168.91 198.12 0)
			(effects
				(font
					(size 1.27 1.27)
					(thickness 0.15)
				)
				(justify left bottom)
				(hide yes)
			)
		)
		(property "License" "Apache-2.0"
			(at 168.91 200.66 0)
			(effects
				(font
					(size 1.27 1.27)
					(thickness 0.15)
				)
				(justify left bottom)
				(hide yes)
			)
		)
		(pin "1"
		)
		(instances
			(project "artix-dc-scm"
				(path ""
					(reference "#PWR0115")
					(unit 1)
				)
			)
		)
	)
	(symbol
		(lib_id "antmicropower:GND")
		(at 266.7 73.66 0)
		(unit 1)
		(exclude_from_sim no)
		(in_bom yes)
		(on_board yes)
		(dnp no)
		(property "Reference" "#PWR0169"
			(at 266.7 80.01 0)
			(effects
				(font
					(size 1.27 1.27)
				)
				(hide yes)
			)
		)
		(property "Value" "GND"
			(at 266.7 77.47 0)
			(effects
				(font
					(size 1.27 1.27)
				)
			)
		)
		(property "Footprint" ""
			(at 266.7 73.66 0)
			(effects
				(font
					(size 1.27 1.27)
				)
				(hide yes)
			)
		)
		(property "Datasheet" ""
			(at 266.7 73.66 0)
			(effects
				(font
					(size 1.27 1.27)
				)
				(hide yes)
			)
		)
		(property "Description" ""
			(at 266.7 73.66 0)
			(effects
				(font
					(size 1.27 1.27)
				)
				(hide yes)
			)
		)
		(property "Author" "Antmicro"
			(at 275.59 81.28 0)
			(effects
				(font
					(size 1.27 1.27)
					(thickness 0.15)
				)
				(justify left bottom)
				(hide yes)
			)
		)
		(property "License" "Apache-2.0"
			(at 275.59 83.82 0)
			(effects
				(font
					(size 1.27 1.27)
					(thickness 0.15)
				)
				(justify left bottom)
				(hide yes)
			)
		)
		(pin "1"
		)
		(instances
			(project "artix-dc-scm"
				(path ""
					(reference "#PWR0169")
					(unit 1)
				)
			)
		)
	)
	(symbol
		(lib_id "antmicropower:GND")
		(at 274.32 92.71 0)
		(unit 1)
		(exclude_from_sim no)
		(in_bom yes)
		(on_board yes)
		(dnp no)
		(property "Reference" "#PWR0172"
			(at 274.32 99.06 0)
			(effects
				(font
					(size 1.27 1.27)
				)
				(hide yes)
			)
		)
		(property "Value" "GND"
			(at 274.32 96.52 0)
			(effects
				(font
					(size 1.27 1.27)
				)
			)
		)
		(property "Footprint" ""
			(at 274.32 92.71 0)
			(effects
				(font
					(size 1.27 1.27)
				)
				(hide yes)
			)
		)
		(property "Datasheet" ""
			(at 274.32 92.71 0)
			(effects
				(font
					(size 1.27 1.27)
				)
				(hide yes)
			)
		)
		(property "Description" ""
			(at 274.32 92.71 0)
			(effects
				(font
					(size 1.27 1.27)
				)
				(hide yes)
			)
		)
		(property "Author" "Antmicro"
			(at 283.21 100.33 0)
			(effects
				(font
					(size 1.27 1.27)
					(thickness 0.15)
				)
				(justify left bottom)
				(hide yes)
			)
		)
		(property "License" "Apache-2.0"
			(at 283.21 102.87 0)
			(effects
				(font
					(size 1.27 1.27)
					(thickness 0.15)
				)
				(justify left bottom)
				(hide yes)
			)
		)
		(pin "1"
		)
		(instances
			(project "artix-dc-scm"
				(path ""
					(reference "#PWR0172")
					(unit 1)
				)
			)
		)
	)
	(symbol
		(lib_id "antmicropower:GND")
		(at 283.21 92.71 0)
		(unit 1)
		(exclude_from_sim no)
		(in_bom yes)
		(on_board yes)
		(dnp no)
		(property "Reference" "#PWR0170"
			(at 283.21 99.06 0)
			(effects
				(font
					(size 1.27 1.27)
				)
				(hide yes)
			)
		)
		(property "Value" "GND"
			(at 283.21 96.52 0)
			(effects
				(font
					(size 1.27 1.27)
				)
			)
		)
		(property "Footprint" ""
			(at 283.21 92.71 0)
			(effects
				(font
					(size 1.27 1.27)
				)
				(hide yes)
			)
		)
		(property "Datasheet" ""
			(at 283.21 92.71 0)
			(effects
				(font
					(size 1.27 1.27)
				)
				(hide yes)
			)
		)
		(property "Description" ""
			(at 283.21 92.71 0)
			(effects
				(font
					(size 1.27 1.27)
				)
				(hide yes)
			)
		)
		(property "Author" "Antmicro"
			(at 292.1 100.33 0)
			(effects
				(font
					(size 1.27 1.27)
					(thickness 0.15)
				)
				(justify left bottom)
				(hide yes)
			)
		)
		(property "License" "Apache-2.0"
			(at 292.1 102.87 0)
			(effects
				(font
					(size 1.27 1.27)
					(thickness 0.15)
				)
				(justify left bottom)
				(hide yes)
			)
		)
		(pin "1"
		)
		(instances
			(project "artix-dc-scm"
				(path ""
					(reference "#PWR0170")
					(unit 1)
				)
			)
		)
	)
	(symbol
		(lib_id "antmicropower:GND")
		(at 290.83 92.71 0)
		(unit 1)
		(exclude_from_sim no)
		(in_bom yes)
		(on_board yes)
		(dnp no)
		(property "Reference" "#PWR0171"
			(at 290.83 99.06 0)
			(effects
				(font
					(size 1.27 1.27)
				)
				(hide yes)
			)
		)
		(property "Value" "GND"
			(at 290.83 96.52 0)
			(effects
				(font
					(size 1.27 1.27)
				)
			)
		)
		(property "Footprint" ""
			(at 290.83 92.71 0)
			(effects
				(font
					(size 1.27 1.27)
				)
				(hide yes)
			)
		)
		(property "Datasheet" ""
			(at 290.83 92.71 0)
			(effects
				(font
					(size 1.27 1.27)
				)
				(hide yes)
			)
		)
		(property "Description" ""
			(at 290.83 92.71 0)
			(effects
				(font
					(size 1.27 1.27)
				)
				(hide yes)
			)
		)
		(property "Author" "Antmicro"
			(at 299.72 100.33 0)
			(effects
				(font
					(size 1.27 1.27)
					(thickness 0.15)
				)
				(justify left bottom)
				(hide yes)
			)
		)
		(property "License" "Apache-2.0"
			(at 299.72 102.87 0)
			(effects
				(font
					(size 1.27 1.27)
					(thickness 0.15)
				)
				(justify left bottom)
				(hide yes)
			)
		)
		(pin "1"
		)
		(instances
			(project "artix-dc-scm"
				(path ""
					(reference "#PWR0171")
					(unit 1)
				)
			)
		)
	)
	(symbol
		(lib_id "antmicropower:GND")
		(at 160.02 113.03 0)
		(unit 1)
		(exclude_from_sim no)
		(in_bom yes)
		(on_board yes)
		(dnp no)
		(property "Reference" "#PWR0141"
			(at 160.02 119.38 0)
			(effects
				(font
					(size 1.27 1.27)
				)
				(hide yes)
			)
		)
		(property "Value" "GND"
			(at 160.02 116.84 0)
			(effects
				(font
					(size 1.27 1.27)
				)
			)
		)
		(property "Footprint" ""
			(at 160.02 113.03 0)
			(effects
				(font
					(size 1.27 1.27)
				)
				(hide yes)
			)
		)
		(property "Datasheet" ""
			(at 160.02 113.03 0)
			(effects
				(font
					(size 1.27 1.27)
				)
				(hide yes)
			)
		)
		(property "Description" ""
			(at 160.02 113.03 0)
			(effects
				(font
					(size 1.27 1.27)
				)
				(hide yes)
			)
		)
		(property "Author" "Antmicro"
			(at 168.91 120.65 0)
			(effects
				(font
					(size 1.27 1.27)
					(thickness 0.15)
				)
				(justify left bottom)
				(hide yes)
			)
		)
		(property "License" "Apache-2.0"
			(at 168.91 123.19 0)
			(effects
				(font
					(size 1.27 1.27)
					(thickness 0.15)
				)
				(justify left bottom)
				(hide yes)
			)
		)
		(pin "1"
		)
		(instances
			(project "artix-dc-scm"
				(path ""
					(reference "#PWR0141")
					(unit 1)
				)
			)
		)
	)
	(symbol
		(lib_id "antmicropower:GND")
		(at 270.51 167.64 0)
		(unit 1)
		(exclude_from_sim no)
		(in_bom yes)
		(on_board yes)
		(dnp no)
		(property "Reference" "#PWR0180"
			(at 270.51 173.99 0)
			(effects
				(font
					(size 1.27 1.27)
				)
				(hide yes)
			)
		)
		(property "Value" "GND"
			(at 270.51 171.45 0)
			(effects
				(font
					(size 1.27 1.27)
				)
			)
		)
		(property "Footprint" ""
			(at 270.51 167.64 0)
			(effects
				(font
					(size 1.27 1.27)
				)
				(hide yes)
			)
		)
		(property "Datasheet" ""
			(at 270.51 167.64 0)
			(effects
				(font
					(size 1.27 1.27)
				)
				(hide yes)
			)
		)
		(property "Description" ""
			(at 270.51 167.64 0)
			(effects
				(font
					(size 1.27 1.27)
				)
				(hide yes)
			)
		)
		(property "Author" "Antmicro"
			(at 279.4 175.26 0)
			(effects
				(font
					(size 1.27 1.27)
					(thickness 0.15)
				)
				(justify left bottom)
				(hide yes)
			)
		)
		(property "License" "Apache-2.0"
			(at 279.4 177.8 0)
			(effects
				(font
					(size 1.27 1.27)
					(thickness 0.15)
				)
				(justify left bottom)
				(hide yes)
			)
		)
		(pin "1"
		)
		(instances
			(project "artix-dc-scm"
				(path ""
					(reference "#PWR0180")
					(unit 1)
				)
			)
		)
	)
	(symbol
		(lib_id "antmicropower:GND")
		(at 295.91 167.64 0)
		(unit 1)
		(exclude_from_sim no)
		(in_bom yes)
		(on_board yes)
		(dnp no)
		(property "Reference" "#PWR0182"
			(at 295.91 173.99 0)
			(effects
				(font
					(size 1.27 1.27)
				)
				(hide yes)
			)
		)
		(property "Value" "GND"
			(at 295.91 171.45 0)
			(effects
				(font
					(size 1.27 1.27)
				)
			)
		)
		(property "Footprint" ""
			(at 295.91 167.64 0)
			(effects
				(font
					(size 1.27 1.27)
				)
				(hide yes)
			)
		)
		(property "Datasheet" ""
			(at 295.91 167.64 0)
			(effects
				(font
					(size 1.27 1.27)
				)
				(hide yes)
			)
		)
		(property "Description" ""
			(at 295.91 167.64 0)
			(effects
				(font
					(size 1.27 1.27)
				)
				(hide yes)
			)
		)
		(property "Author" "Antmicro"
			(at 304.8 175.26 0)
			(effects
				(font
					(size 1.27 1.27)
					(thickness 0.15)
				)
				(justify left bottom)
				(hide yes)
			)
		)
		(property "License" "Apache-2.0"
			(at 304.8 177.8 0)
			(effects
				(font
					(size 1.27 1.27)
					(thickness 0.15)
				)
				(justify left bottom)
				(hide yes)
			)
		)
		(pin "1"
		)
		(instances
			(project "artix-dc-scm"
				(path ""
					(reference "#PWR0182")
					(unit 1)
				)
			)
		)
	)
	(symbol
		(lib_id "antmicropower:GND")
		(at 168.91 92.71 0)
		(unit 1)
		(exclude_from_sim no)
		(in_bom yes)
		(on_board yes)
		(dnp no)
		(property "Reference" "#PWR0120"
			(at 168.91 99.06 0)
			(effects
				(font
					(size 1.27 1.27)
				)
				(hide yes)
			)
		)
		(property "Value" "GND"
			(at 168.91 96.52 0)
			(effects
				(font
					(size 1.27 1.27)
				)
			)
		)
		(property "Footprint" ""
			(at 168.91 92.71 0)
			(effects
				(font
					(size 1.27 1.27)
				)
				(hide yes)
			)
		)
		(property "Datasheet" ""
			(at 168.91 92.71 0)
			(effects
				(font
					(size 1.27 1.27)
				)
				(hide yes)
			)
		)
		(property "Description" ""
			(at 168.91 92.71 0)
			(effects
				(font
					(size 1.27 1.27)
				)
				(hide yes)
			)
		)
		(property "Author" "Antmicro"
			(at 177.8 100.33 0)
			(effects
				(font
					(size 1.27 1.27)
					(thickness 0.15)
				)
				(justify left bottom)
				(hide yes)
			)
		)
		(property "License" "Apache-2.0"
			(at 177.8 102.87 0)
			(effects
				(font
					(size 1.27 1.27)
					(thickness 0.15)
				)
				(justify left bottom)
				(hide yes)
			)
		)
		(pin "1"
		)
		(instances
			(project "artix-dc-scm"
				(path ""
					(reference "#PWR0120")
					(unit 1)
				)
			)
		)
	)
	(symbol
		(lib_id "antmicropower:GND")
		(at 299.72 73.66 0)
		(unit 1)
		(exclude_from_sim no)
		(in_bom yes)
		(on_board yes)
		(dnp no)
		(property "Reference" "#PWR0175"
			(at 299.72 80.01 0)
			(effects
				(font
					(size 1.27 1.27)
				)
				(hide yes)
			)
		)
		(property "Value" "GND"
			(at 299.72 77.47 0)
			(effects
				(font
					(size 1.27 1.27)
				)
			)
		)
		(property "Footprint" ""
			(at 299.72 73.66 0)
			(effects
				(font
					(size 1.27 1.27)
				)
				(hide yes)
			)
		)
		(property "Datasheet" ""
			(at 299.72 73.66 0)
			(effects
				(font
					(size 1.27 1.27)
				)
				(hide yes)
			)
		)
		(property "Description" ""
			(at 299.72 73.66 0)
			(effects
				(font
					(size 1.27 1.27)
				)
				(hide yes)
			)
		)
		(property "Author" "Antmicro"
			(at 308.61 81.28 0)
			(effects
				(font
					(size 1.27 1.27)
					(thickness 0.15)
				)
				(justify left bottom)
				(hide yes)
			)
		)
		(property "License" "Apache-2.0"
			(at 308.61 83.82 0)
			(effects
				(font
					(size 1.27 1.27)
					(thickness 0.15)
				)
				(justify left bottom)
				(hide yes)
			)
		)
		(pin "1"
		)
		(instances
			(project "artix-dc-scm"
				(path ""
					(reference "#PWR0175")
					(unit 1)
				)
			)
		)
	)
	(symbol
		(lib_id "antmicropower:GND")
		(at 152.4 92.71 0)
		(unit 1)
		(exclude_from_sim no)
		(in_bom yes)
		(on_board yes)
		(dnp no)
		(property "Reference" "#PWR0116"
			(at 152.4 99.06 0)
			(effects
				(font
					(size 1.27 1.27)
				)
				(hide yes)
			)
		)
		(property "Value" "GND"
			(at 152.4 96.52 0)
			(effects
				(font
					(size 1.27 1.27)
				)
			)
		)
		(property "Footprint" ""
			(at 152.4 92.71 0)
			(effects
				(font
					(size 1.27 1.27)
				)
				(hide yes)
			)
		)
		(property "Datasheet" ""
			(at 152.4 92.71 0)
			(effects
				(font
					(size 1.27 1.27)
				)
				(hide yes)
			)
		)
		(property "Description" ""
			(at 152.4 92.71 0)
			(effects
				(font
					(size 1.27 1.27)
				)
				(hide yes)
			)
		)
		(property "Author" "Antmicro"
			(at 161.29 100.33 0)
			(effects
				(font
					(size 1.27 1.27)
					(thickness 0.15)
				)
				(justify left bottom)
				(hide yes)
			)
		)
		(property "License" "Apache-2.0"
			(at 161.29 102.87 0)
			(effects
				(font
					(size 1.27 1.27)
					(thickness 0.15)
				)
				(justify left bottom)
				(hide yes)
			)
		)
		(pin "1"
		)
		(instances
			(project "artix-dc-scm"
				(path ""
					(reference "#PWR0116")
					(unit 1)
				)
			)
		)
	)
	(symbol
		(lib_id "antmicropower:GND")
		(at 323.85 73.66 0)
		(unit 1)
		(exclude_from_sim no)
		(in_bom yes)
		(on_board yes)
		(dnp no)
		(property "Reference" "#PWR0179"
			(at 323.85 80.01 0)
			(effects
				(font
					(size 1.27 1.27)
				)
				(hide yes)
			)
		)
		(property "Value" "GND"
			(at 323.85 77.47 0)
			(effects
				(font
					(size 1.27 1.27)
				)
			)
		)
		(property "Footprint" ""
			(at 323.85 73.66 0)
			(effects
				(font
					(size 1.27 1.27)
				)
				(hide yes)
			)
		)
		(property "Datasheet" ""
			(at 323.85 73.66 0)
			(effects
				(font
					(size 1.27 1.27)
				)
				(hide yes)
			)
		)
		(property "Description" ""
			(at 323.85 73.66 0)
			(effects
				(font
					(size 1.27 1.27)
				)
				(hide yes)
			)
		)
		(property "Author" "Antmicro"
			(at 332.74 81.28 0)
			(effects
				(font
					(size 1.27 1.27)
					(thickness 0.15)
				)
				(justify left bottom)
				(hide yes)
			)
		)
		(property "License" "Apache-2.0"
			(at 332.74 83.82 0)
			(effects
				(font
					(size 1.27 1.27)
					(thickness 0.15)
				)
				(justify left bottom)
				(hide yes)
			)
		)
		(pin "1"
		)
		(instances
			(project "artix-dc-scm"
				(path ""
					(reference "#PWR0179")
					(unit 1)
				)
			)
		)
	)
	(symbol
		(lib_id "antmicropower:PWR_FLAG")
		(at 259.08 86.36 0)
		(unit 1)
		(exclude_from_sim no)
		(in_bom yes)
		(on_board yes)
		(dnp no)
		(property "Reference" "#FLG0103"
			(at 259.08 84.455 0)
			(effects
				(font
					(size 1.27 1.27)
				)
				(hide yes)
			)
		)
		(property "Value" "PWR_FLAG"
			(at 259.08 82.55 0)
			(effects
				(font
					(size 1.27 1.27)
				)
			)
		)
		(property "Footprint" ""
			(at 259.08 86.36 0)
			(effects
				(font
					(size 1.27 1.27)
				)
				(hide yes)
			)
		)
		(property "Datasheet" ""
			(at 259.08 86.36 0)
			(effects
				(font
					(size 1.27 1.27)
				)
				(hide yes)
			)
		)
		(property "Description" ""
			(at 259.08 86.36 0)
			(effects
				(font
					(size 1.27 1.27)
				)
				(hide yes)
			)
		)
		(pin "1"
		)
		(instances
			(project "artix-dc-scm"
				(path ""
					(reference "#FLG0103")
					(unit 1)
				)
			)
		)
	)
	(symbol
		(lib_id "antmicropower:GND")
		(at 152.4 113.03 0)
		(unit 1)
		(exclude_from_sim no)
		(in_bom yes)
		(on_board yes)
		(dnp no)
		(property "Reference" "#PWR0145"
			(at 152.4 119.38 0)
			(effects
				(font
					(size 1.27 1.27)
				)
				(hide yes)
			)
		)
		(property "Value" "GND"
			(at 152.4 116.84 0)
			(effects
				(font
					(size 1.27 1.27)
				)
			)
		)
		(property "Footprint" ""
			(at 152.4 113.03 0)
			(effects
				(font
					(size 1.27 1.27)
				)
				(hide yes)
			)
		)
		(property "Datasheet" ""
			(at 152.4 113.03 0)
			(effects
				(font
					(size 1.27 1.27)
				)
				(hide yes)
			)
		)
		(property "Description" ""
			(at 152.4 113.03 0)
			(effects
				(font
					(size 1.27 1.27)
				)
				(hide yes)
			)
		)
		(property "Author" "Antmicro"
			(at 161.29 120.65 0)
			(effects
				(font
					(size 1.27 1.27)
					(thickness 0.15)
				)
				(justify left bottom)
				(hide yes)
			)
		)
		(property "License" "Apache-2.0"
			(at 161.29 123.19 0)
			(effects
				(font
					(size 1.27 1.27)
					(thickness 0.15)
				)
				(justify left bottom)
				(hide yes)
			)
		)
		(pin "1"
		)
		(instances
			(project "artix-dc-scm"
				(path ""
					(reference "#PWR0145")
					(unit 1)
				)
			)
		)
	)
	(symbol
		(lib_id "antmicropower:GND")
		(at 274.32 73.66 0)
		(unit 1)
		(exclude_from_sim no)
		(in_bom yes)
		(on_board yes)
		(dnp no)
		(property "Reference" "#PWR0177"
			(at 274.32 80.01 0)
			(effects
				(font
					(size 1.27 1.27)
				)
				(hide yes)
			)
		)
		(property "Value" "GND"
			(at 274.32 77.47 0)
			(effects
				(font
					(size 1.27 1.27)
				)
			)
		)
		(property "Footprint" ""
			(at 274.32 73.66 0)
			(effects
				(font
					(size 1.27 1.27)
				)
				(hide yes)
			)
		)
		(property "Datasheet" ""
			(at 274.32 73.66 0)
			(effects
				(font
					(size 1.27 1.27)
				)
				(hide yes)
			)
		)
		(property "Description" ""
			(at 274.32 73.66 0)
			(effects
				(font
					(size 1.27 1.27)
				)
				(hide yes)
			)
		)
		(property "Author" "Antmicro"
			(at 283.21 81.28 0)
			(effects
				(font
					(size 1.27 1.27)
					(thickness 0.15)
				)
				(justify left bottom)
				(hide yes)
			)
		)
		(property "License" "Apache-2.0"
			(at 283.21 83.82 0)
			(effects
				(font
					(size 1.27 1.27)
					(thickness 0.15)
				)
				(justify left bottom)
				(hide yes)
			)
		)
		(pin "1"
		)
		(instances
			(project "artix-dc-scm"
				(path ""
					(reference "#PWR0177")
					(unit 1)
				)
			)
		)
	)
	(symbol
		(lib_id "antmicropower:GND")
		(at 307.34 73.66 0)
		(unit 1)
		(exclude_from_sim no)
		(in_bom yes)
		(on_board yes)
		(dnp no)
		(property "Reference" "#PWR0176"
			(at 307.34 80.01 0)
			(effects
				(font
					(size 1.27 1.27)
				)
				(hide yes)
			)
		)
		(property "Value" "GND"
			(at 307.34 77.47 0)
			(effects
				(font
					(size 1.27 1.27)
				)
			)
		)
		(property "Footprint" ""
			(at 307.34 73.66 0)
			(effects
				(font
					(size 1.27 1.27)
				)
				(hide yes)
			)
		)
		(property "Datasheet" ""
			(at 307.34 73.66 0)
			(effects
				(font
					(size 1.27 1.27)
				)
				(hide yes)
			)
		)
		(property "Description" ""
			(at 307.34 73.66 0)
			(effects
				(font
					(size 1.27 1.27)
				)
				(hide yes)
			)
		)
		(property "Author" "Antmicro"
			(at 316.23 81.28 0)
			(effects
				(font
					(size 1.27 1.27)
					(thickness 0.15)
				)
				(justify left bottom)
				(hide yes)
			)
		)
		(property "License" "Apache-2.0"
			(at 316.23 83.82 0)
			(effects
				(font
					(size 1.27 1.27)
					(thickness 0.15)
				)
				(justify left bottom)
				(hide yes)
			)
		)
		(pin "1"
		)
		(instances
			(project "artix-dc-scm"
				(path ""
					(reference "#PWR0176")
					(unit 1)
				)
			)
		)
	)
	(symbol
		(lib_id "antmicropower:GND")
		(at 144.78 92.71 0)
		(unit 1)
		(exclude_from_sim no)
		(in_bom yes)
		(on_board yes)
		(dnp no)
		(property "Reference" "#PWR0108"
			(at 144.78 99.06 0)
			(effects
				(font
					(size 1.27 1.27)
				)
				(hide yes)
			)
		)
		(property "Value" "GND"
			(at 144.78 96.52 0)
			(effects
				(font
					(size 1.27 1.27)
				)
			)
		)
		(property "Footprint" ""
			(at 144.78 92.71 0)
			(effects
				(font
					(size 1.27 1.27)
				)
				(hide yes)
			)
		)
		(property "Datasheet" ""
			(at 144.78 92.71 0)
			(effects
				(font
					(size 1.27 1.27)
				)
				(hide yes)
			)
		)
		(property "Description" ""
			(at 144.78 92.71 0)
			(effects
				(font
					(size 1.27 1.27)
				)
				(hide yes)
			)
		)
		(property "Author" "Antmicro"
			(at 153.67 100.33 0)
			(effects
				(font
					(size 1.27 1.27)
					(thickness 0.15)
				)
				(justify left bottom)
				(hide yes)
			)
		)
		(property "License" "Apache-2.0"
			(at 153.67 102.87 0)
			(effects
				(font
					(size 1.27 1.27)
					(thickness 0.15)
				)
				(justify left bottom)
				(hide yes)
			)
		)
		(pin "1"
		)
		(instances
			(project "artix-dc-scm"
				(path ""
					(reference "#PWR0108")
					(unit 1)
				)
			)
		)
	)
)
